5
5
4
4
3
3
2
2
1
1
D D
C C
B B
A A
Honey Badger 
Base Board_LSI 
Title 
Size Document Number Rev 
Date: Sheet o f 
Honey badger_LSI Base Board 1B
COVER PAGE
A4
1 71Tuesday, January 20, 2015
Honey badger_LSI Base Board
http://www.wiwynn.com
8F, 90, Sec.1, Xintai 5th Rd., Xizhi Dist.,
New Taipei City 22102, Taiwan (R.O.C.)
Title 
Size Document Number Rev 
Date: Sheet o f 
Honey badger_LSI Base Board 1B
COVER PAGE
A4
1 71Tuesday, January 20, 2015
Honey badger_LSI Base Board
http://www.wiwynn.com
8F, 90, Sec.1, Xintai 5th Rd., Xizhi Dist.,
New Taipei City 22102, Taiwan (R.O.C.)
Title 
Size Document Number Rev 
Date: Sheet o f 
Honey badger_LSI Base Board 1B
COVER PAGE
A4
1 71Tuesday, January 20, 2015
Honey badger_LSI Base Board
http://www.wiwynn.com
8F, 90, Sec.1, Xintai 5th Rd., Xizhi Dist.,
New Taipei City 22102, Taiwan (R.O.C.)



5
5
4
4
3
3
2
2
1
1
D D
C C
B B
A A
TABLE OF CONTENTS 
PWRSW_P0V9_E_TPS53355 12V-DCIN_ADM1278 HSC 
CLOCK TREE SAS3x24R POWER_2 SAS3x24R SAS PHY A SAS3008_PCIE & SAS TABLE OF CONTENTS I2C\SMBUS DIAGRAM POWER SEQUENCE POWER DISTRIBUTION DIAGRAM STACK-UP INFORMATION POWER FLOW SYSTEM BLOCK DIAGRAM 
52 51 50 57 56 55 54 53 63 62 61 60 59 58 
40 
67 66 65 64 47 44 43 41 42 
12 39 
45 48 
AST1250 I2C DDR LPC 
49 46 
17 16 15 14 13 22 21 20 19 18 30 29 28 27 24 23 05 04 03 02 31 10 11 08 09 06 33 32 
68 
07 34 26 25 37 36 01 
COVER PAGE 
35 38 
PWRMOS_P1V8_C & P1V8_E PWRSW_P0V955_C_VT235WFQX PWRMOS_P3V3 
SAS3x24R_UART LEVEL SHIFT SAS3x24R POWER&GND EXT MINI_SAS CONN x16 PCIe CONN FOR uSEVRVER HEARTBEAT CIRCUITRY POWER/ENCLOUSRE LED SAS3x24R MINI SAS&REDRIVER 10G MEZZ CARD RTC PCIe GOLDEN FINGER FOR SAS HDD POWER & FAULT_LED JTAG BUNDARY SCAN BLANK 
AST1250 FAN ADC VGA AST1250 UART LAN SPI AST1250 I2C DEVICES USB2.0 x1 AST1250 Power PWRSW_P3V3_STBY_TPS53318 DEBUG PORT I2C  BUFFER&LEVEL SHIFT PWRSW_P5V_STBY_TPS53312 PWRLDO_P1V53_STBY_TPS74801 12V-DCIN_SERVER BOARD PWRLDO_P1V26_STBY_TPS74801 JTAG TOPOLOGY DEBUG PORT TOPOLOGY PWRSW_P1V8_STBY_TPS53318 POWER/RESET_BUTTON PWRSW_P1V5_E 
SAS3008_POWER&GND SAS3008_POWER_2 SAS3008_POWER_1 SAS3008_MISC SAS3x24R MEMORIES SAS3x24R LED&GPIO SAS3x24R SAS PHY B & I2C SAS3008_RESERVE SAS3008_RESERVE SAS3008_EEPROM SAS300_GPIO & USB & ETH RESERVE SAS3x24R POWER_1 SAS3x24R MISC 
PWRLDO_P1V5_C_TPS74801 AST1250 Stapping 
PAGE TITLE 
PAGE TITLE 
PAGE 
PAGE 
SAS3008_FLASH 
PAGE TITLE 
PAGE 
AST1250_VOLTAGE SENSE ETHERNET_PHY_BCM5221 LAN CONNECTOR BLANK 
69 70 71 
BLANK BLANK 
Title 
Size Document Number R e v 
Date: Sheet 
o f 
Honey badger_LSI Base Board 1B
TABLE OF CONTENTS
A3
2 71Tuesday, January 20, 2015
Honey badger_LSI Base Board
http://www.wiwynn.com
8F, 90, Sec.1, Xintai 5th Rd., Xizhi Dist.,
New Taipei City 22102, Taiwan (R.O.C.)
Title 
Size Document Number R e v 
Date: Sheet 
o f 
Honey badger_LSI Base Board 1B
TABLE OF CONTENTS
A3
2 71Tuesday, January 20, 2015
Honey badger_LSI Base Board
http://www.wiwynn.com
8F, 90, Sec.1, Xintai 5th Rd., Xizhi Dist.,
New Taipei City 22102, Taiwan (R.O.C.)
Title 
Size Document Number R e v 
Date: Sheet 
o f 
Honey badger_LSI Base Board 1B
TABLE OF CONTENTS
A3
2 71Tuesday, January 20, 2015
Honey badger_LSI Base Board
http://www.wiwynn.com
8F, 90, Sec.1, Xintai 5th Rd., Xizhi Dist.,
New Taipei City 22102, Taiwan (R.O.C.)



5
5
4
4
3
3
2
2
1
1
D D
C C
B B
A A
Title 
Size Document Number R e v 
Date: Sheet 
o f 
Honey badger_LSI Base Board 1B
SYSTEM BLOCK DIAGRAM
A3
3 71Tuesday, January 20, 2015
Honey badger_LSI Base Board
http://www.wiwynn.com
8F, 90, Sec.1, Xintai 5th Rd., Xizhi Dist.,
New Taipei City 22102, Taiwan (R.O.C.)
Title 
Size Document Number R e v 
Date: Sheet 
o f 
Honey badger_LSI Base Board 1B
SYSTEM BLOCK DIAGRAM
A3
3 71Tuesday, January 20, 2015
Honey badger_LSI Base Board
http://www.wiwynn.com
8F, 90, Sec.1, Xintai 5th Rd., Xizhi Dist.,
New Taipei City 22102, Taiwan (R.O.C.)
Title 
Size Document Number R e v 
Date: Sheet 
o f 
Honey badger_LSI Base Board 1B
SYSTEM BLOCK DIAGRAM
A3
3 71Tuesday, January 20, 2015
Honey badger_LSI Base Board
http://www.wiwynn.com
8F, 90, Sec.1, Xintai 5th Rd., Xizhi Dist.,
New Taipei City 22102, Taiwan (R.O.C.)



5
5
4
4
3
3
2
2
1
1
D D
C C
B B
A A
P1V8_STBY 
P3V3_STBY  375mA 
P3V3 
P3V3_STBY 
P3V3_STBY 
P0V955_C 
P1V8_C 
5.675A 
10G Card (LAN) 
P12V 
SAS LSI 3008 
P3V3  3A 
P12V 0.5A 
P1V5_C   0.36A 
P1V8_C   0.66A 
P0V955_C   14.37A 
3.3V   3.575A 
P3V3_SBTY 
1.8V   2.42A P1V8_STBY 
12.5V 
Current Limit FET Switch 
Low Rds on 
VR LINEAR 
P1V8_E 
P0V9_E 
SAS LSI 3x24R-LP 
P0V9_E  21.85A 
P1V8_E   0.11A 
USB2 
P5V_STBY   1A 
P1V53_STBY 
P1V26_STBY 
P5V_STBY 
P1V5_C 
P12V_MSB 7.26A 
uServer Board 
OCP=>7.26x1.5=10.89A 
BMC AST1250 
P1V53_STBY  370mA 
P3V3_STBY   200mA 
P1V26_STBY   695mA 
P1V8_STBY   225mA 
P12V 
1.638 
0.983A 
0.363A 
0.833A 
OCP=>5.61x1.5=8.4A 
0.5A 
7.26A 
VR SWITCHING 
P0V9_E 
0.9V   21.85A 
P5V_STBY 5V  2A 
P1V5_C 
1.5V   0.36A 
P1V26_STBY 
1.26V   700mA 
1.53V   370mA 
P1V53_STBY 
Hot Swap 
~22.5W 
~15W 
P5V_STBY 
P5V_STBY  1A 
P1V5_E  1.75A P1V5_E 
1.5V   1.75A 
0.218A P1V5_E 
0.955V   14.37A 
P0V955_C 1.14A 
Title 
Size Document Number R e v 
Date: Sheet 
o f 
Honey badger_LSI Base Board 1B
POWER DISTRIBUTION DIAGRAM
A3
4 71Tuesday, January 20, 2015
Honey badger_LSI Base Board
http://www.wiwynn.com
8F, 90, Sec.1, Xintai 5th Rd., Xizhi Dist.,
New Taipei City 22102, Taiwan (R.O.C.)
Title 
Size Document Number R e v 
Date: Sheet 
o f 
Honey badger_LSI Base Board 1B
POWER DISTRIBUTION DIAGRAM
A3
4 71Tuesday, January 20, 2015
Honey badger_LSI Base Board
http://www.wiwynn.com
8F, 90, Sec.1, Xintai 5th Rd., Xizhi Dist.,
New Taipei City 22102, Taiwan (R.O.C.)
Title 
Size Document Number R e v 
Date: Sheet 
o f 
Honey badger_LSI Base Board 1B
POWER DISTRIBUTION DIAGRAM
A3
4 71Tuesday, January 20, 2015
Honey badger_LSI Base Board
http://www.wiwynn.com
8F, 90, Sec.1, Xintai 5th Rd., Xizhi Dist.,
New Taipei City 22102, Taiwan (R.O.C.)



5
5
4
4
3
3
2
2
1
1
D D
C C
B B
A A
10kΩ 
P3V3_STBY_VREG(5V) 
P3V3_STBY_PG TPS53318DQPR-GP 
P3V3_STBY 
P3V3_STBY_EN_R 
EN 
In 
PGOOD 
OUT 
(OD) 
P12V 
Switching 
SYS_RST 
uServer board 
10kΩ 
P5V_STBY_VRG5(5.5V) 
PGOOD 
(OD) 
OUT 
P1V8_STBY 
In 
EN 
TPS53318DQPR-GP 
P1V8_STBY_PG 
Switching 
P12V 
10kΩ 
P1V8_STBY_VRG5(5V) 
POWER CONN 
(PCIE X16) 
P5V_STBY 
P12V_PCIE P12V_PCIE 
(OD) 
OUT 
PGOOD 
In 
EN 
ADM1278K2ACPZKRLKGP 
2mΩ 
P5V_STBY_PG 
PRSNT 
TPS53312RRTR-GP 
ADM1178K2ARMZKR7KGP 
10mΩ P12V_MSB 
P12V_PCIE 
AND 
Gate 
P3V3_EN(from BMC) 
P3V3_STBY 
4.02KΩ 
4.7KΩ 
P1V8_C 
P3V3_STBY 
4.7KΩ 
P1V8_C P1V8_STBY 
PWRGD_P1V8_PG 
4.02KΩ 
P3V3_STBY P12V 
20KΩ 
P1V8_EN 
P3V3_STBY 
1KΩ 
Power button by 
BMC or User 
10kΩ 
P3V3_STBY 
P12V 
5.36kΩ 
2.05kΩ 
10kΩ 
P1V8_STBY 
LDO 
2.7kΩ 
P1V8_STBY 
LDO 
P1V5_C 
OUT In 
PGOOD 
EN 
P1V53_STBY 
OUT In 
(OD) 
P1V5_PG 
PGOOD 
EN (OD) 
TPS74801RGW-GP 
P1V53_STBY_PG 
TPS74801RGW-GP 
P3V3_STBY 
P3V3_STBY 
PWRGD_P1V2_PG 
2.7kΩ 
P1V8_STBY 
LDO 
P1V26_STBY 
OUT In 
PGOOD 
EN (OD) 
P1V26_STBY_PG 
TPS74801RGW-GP 
P3V3_STBY 
P12V P12V_MSB 
Standby mode 
Power on mode 
Switching 
C
10kΩ 
P12V 
Switching 
P1V5_E 
OUT In 
PGOOD 
EN (OD) 
P1V5_E_PG 
TPS53312RGTR-GP 
P1V5_VREG 
P1V8_E P1V8_STBY 
4.02KΩ 
P3V3_STBY P12V 
10KΩ 
P3V3_STBY 
4.02KΩ 
P3V3_STBY 
4.7KΩ 
P3V3_STBY 
1KΩ 
4.7KΩ 
P1V8_E 
PWRGD_P1V8_E 
10KΩ 
P12V 
G
D
G
S
D
S
P3V3 
D
G S
P3V3_STBY 
20KΩ 
P12V 
1kΩ 
4.02kΩ 
P3V3_STBY 
P3V3_STBY 
4.7KΩ 
P3V3_STBY 
1KΩ 
4.7KΩ 
P3V3 
PWRGD_P3V3 
P12V 
Switching 10kΩ 
P1V5_C P0V955_C 
(OD) 
OUT 
PGOOD 
In 
EN 
P0V955_C_PG VT235WFQX-ADJ-GP 
10kΩ 
P3V3_STBY 
10kΩ 
P12V 
Switching 
P0V9_E 
OUT In 
PGOOD 
EN (OD) 
P0V9_STBY_PG 
TPS53355DQPR-GP 
P1V5_VREG 
P3V3_EN(from P0V9_E PG) 
BMC 
Title 
Size Document Number Re v 
Date: Sheet o f 
Honey badger_LSI Base Board 1B
POWER FLOW
Custom
5 71Tuesday, January 20, 2015
Honey badger_LSI Base Board
http://www.wiwynn.com
8F, 90, Sec.1, Xintai 5th Rd., Xizhi Dist.,
New Taipei City 22102, Taiwan (R.O.C.)
Title 
Size Document Number Re v 
Date: Sheet o f 
Honey badger_LSI Base Board 1B
POWER FLOW
Custom
5 71Tuesday, January 20, 2015
Honey badger_LSI Base Board
http://www.wiwynn.com
8F, 90, Sec.1, Xintai 5th Rd., Xizhi Dist.,
New Taipei City 22102, Taiwan (R.O.C.)
Title 
Size Document Number Re v 
Date: Sheet o f 
Honey badger_LSI Base Board 1B
POWER FLOW
Custom
5 71Tuesday, January 20, 2015
Honey badger_LSI Base Board
http://www.wiwynn.com
8F, 90, Sec.1, Xintai 5th Rd., Xizhi Dist.,
New Taipei City 22102, Taiwan (R.O.C.)



5
5
4
4
3
3
2
2
1
1
D D
C C
B B
A A
P12V 
POWER SEQUENCE DIAGRAM 
 GOLDEN FINGER 
(DPB PCIe x 16) 
SOURCE DESTINATION 
HOT SWAP IC 
  ADM1278 
P12V_PCIE 
P5V_STBY  VR SWT 
(EN:P12V) 
SIGNAL/PWR 
P12V_PCIE 
VR SW SOURCE/10G 
USB 
      VR SWT 
(EN:P5V_STBY PWRGD) BMC/10G P3V3_STBY 
P1V8_STBY BMC 
P0V9_E LSI3x24R 
STANDBY POWER 
P1V8_C 
P1V5_C 
P0V955_C 
LSI3008 
LSI3008 
LSI3008 
P3V3 10G     P3V3_STBY 
(PWR MOS TRANSFER) 
    P1V8_STBY 
(PWR MOS TRANSFER) 
      LDO 
(EN:P1V8_C_PWRGD) 
    PWR BTN 
(BY BMC or USER) BMC PMU_PWRBTN_N 
      VR SWT 
(EN:P1V5_C PWRGD) 
BASE BOARD 
  (BMC) 
PLTRST CPU Board 
PRSNT CPU Board P12V_MSB 
      VR SWT 
(EN:P3V3_STBY PWRGD) 
        LDO 
(EN:P1V8_E PWRGD) 
Initial 12ms 
    P1V8_STBY 
(PWR MOS TRANSFER) LSI3x24R P1V8_E 
      VR SWT 
(EN:P1V8_STBY PWRGD) 
        LDO 
(EN:P1V53_STBY PWRGD) 
P1V53_STBY 
P1V26_STBY 
BMC 
BMC 
NORMAL POWER 
Soft Start 1.26 ms 
Soft Start 5.6 ms 
Soft Start 0.86 ms 
Soft Start 5.6 ms 
Soft Start 0.86 ms 
Soft Start 5.6 ms 
Initial 12ms 
Soft Start 0.86 ms 
Soft Start xx ms 
    P1V8_STBY 
(PWR MOS TRANSFER) LSI3x24R P1V5_E 
Soft Start 1.26ms 
Title 
Size Document Number R e v 
Date: Sheet 
o f 
Honey badger_LSI Base Board 1B
POWER SEQUENCE
A3
6 71Tuesday, January 20, 2015
Honey badger_LSI Base Board
http://www.wiwynn.com
8F, 90, Sec.1, Xintai 5th Rd., Xizhi Dist.,
New Taipei City 22102, Taiwan (R.O.C.)
Title 
Size Document Number R e v 
Date: Sheet 
o f 
Honey badger_LSI Base Board 1B
POWER SEQUENCE
A3
6 71Tuesday, January 20, 2015
Honey badger_LSI Base Board
http://www.wiwynn.com
8F, 90, Sec.1, Xintai 5th Rd., Xizhi Dist.,
New Taipei City 22102, Taiwan (R.O.C.)
Title 
Size Document Number R e v 
Date: Sheet 
o f 
Honey badger_LSI Base Board 1B
POWER SEQUENCE
A3
6 71Tuesday, January 20, 2015
Honey badger_LSI Base Board
http://www.wiwynn.com
8F, 90, Sec.1, Xintai 5th Rd., Xizhi Dist.,
New Taipei City 22102, Taiwan (R.O.C.)



5
5
4
4
3
3
2
2
1
1
D D
C C
B B
A A
XTAL 25MHz 
LSI SAS3008 
ETHER 10G CARD 
SRC4_LRS 
SRC3_LRS 
14.31818MHz 
OSC 
SRC5_LRS 
DIFF1 
DIFF0 
SATA 
DOT96/SRC6 
REF 
9DB833 
DIFF0 
DIFF1 
DIFF2 
SRC_IN 
DIFF3 
OE_0# 
OE_1# 
OE_2# 
OE_3# 
DIFF4 
DIFF5 
100MHz_SAS3008 
100MHz_10G(Primary) 
SRC1_LRS 
9VRS4420 
SRC2_LRS 
LSI SAS3x24R XTAL 25MHz 
Micro Server Card 
BMC AST1250 
50MHz OSC 
PHY BCM5512 
CLOCK 
BUFFER 
MAC1 
MAC2 
NCSI 
100MHz_10G(Secondary) 
Title 
Size Document Number R e v 
Date: Sheet 
o f 
Honey badger_LSI Base Board 1B
CLOCK TREE
A3
7 71Tuesday, January 20, 2015
Honey badger_LSI Base Board
http://www.wiwynn.com
8F, 90, Sec.1, Xintai 5th Rd., Xizhi Dist.,
New Taipei City 22102, Taiwan (R.O.C.)
Title 
Size Document Number R e v 
Date: Sheet 
o f 
Honey badger_LSI Base Board 1B
CLOCK TREE
A3
7 71Tuesday, January 20, 2015
Honey badger_LSI Base Board
http://www.wiwynn.com
8F, 90, Sec.1, Xintai 5th Rd., Xizhi Dist.,
New Taipei City 22102, Taiwan (R.O.C.)
Title 
Size Document Number R e v 
Date: Sheet 
o f 
Honey badger_LSI Base Board 1B
CLOCK TREE
A3
7 71Tuesday, January 20, 2015
Honey badger_LSI Base Board
http://www.wiwynn.com
8F, 90, Sec.1, Xintai 5th Rd., Xizhi Dist.,
New Taipei City 22102, Taiwan (R.O.C.)



5
5
4
4
3
3
2
2
1
1
D D
C C
B B
A A
STACK-UP INFORMATION 
Title 
Size Document Number Rev 
Date: Sheet o f 
Honey badger_LSI Base Board 1B
STACK-UP IMFORMATION
A2
8 71Tuesday, January 20, 2015
Honey badger_LSI Base Board
http://www.wiwynn.com
8F, 90, Sec.1, Xintai 5th Rd., Xizhi Dist.,
New Taipei City 22102, Taiwan (R.O.C.)
Title 
Size Document Number Rev 
Date: Sheet o f 
Honey badger_LSI Base Board 1B
STACK-UP IMFORMATION
A2
8 71Tuesday, January 20, 2015
Honey badger_LSI Base Board
http://www.wiwynn.com
8F, 90, Sec.1, Xintai 5th Rd., Xizhi Dist.,
New Taipei City 22102, Taiwan (R.O.C.)
Title 
Size Document Number Rev 
Date: Sheet o f 
Honey badger_LSI Base Board 1B
STACK-UP IMFORMATION
A2
8 71Tuesday, January 20, 2015
Honey badger_LSI Base Board
http://www.wiwynn.com
8F, 90, Sec.1, Xintai 5th Rd., Xizhi Dist.,
New Taipei City 22102, Taiwan (R.O.C.)



5
5
4
4
3
3
2
2
1
1
D D
C C
B B
A A
4.7KΩ 
4.7KΩ 
10KΩ 
4.75KΩ 
P3V3_STBY 
I2C_CLK/DATA6(M) 
I2C_CLK/DATA14(M) 
P3V3_STBY 
MDC/MDIO 
SMBUS_CLK/DATA/ALERT3(M) 
I2C_CLK/DATA7(M) 
SMB_CLK/DATA/ALERT(M) 
uServer Board 
ETHER10G CARD 
BMC 
AST1250 
I2C_C 
LSI3x24R 
I2C_B 
SMBUS_CLK/DATA/ALERT2(M) 
D
P
B
P1V8_E 
2.2KΩ 
I2C TOPOLOGY 
SMBUS_CLK/DATA/ALERT1(M) 
EXP_I2C_1 
EXP_I2C_2 
I2C_CLK/DATA_2(S) 
I2C_CLK/DATA_1(S) 
I2C_CLK/DATA_3(M) 
P3V3_STBY 
P3V3_STBY 
(M):Master 
(S):Slave 
LSI3008 
I2C_CLK/DATA4(S) 
HOT SWAP IC 
ADM1278 
ADDR: 0x22 
LED DRIVER 
PCA9550 
ADDR: 0xC0 
10KΩ 
P3V3_STBY 
10KΩ 
P3V3_STBY 
SBL_CLK/DATA(M) 
I2C_CLK/DATA8(M) 
I2C_CLK/DATA9(S) 
I2C_CLK/DATA_4(M) 
EXP_I2C_3 
Broadcom 
BCM5221 
I2C_CLK/DATA5(M) 
EEPROM 
AT24C64 
ADDR: 0xA0 
P1V8_C 
SBL 
IOC_I2C_4 
P3V3_STBY 
10KΩ 
P3V3_STBY 
10KΩ 
I2C_CLK/DATA_0(M) 
I2C to GPIO 
PCA9575(HDD POWER) 
ADDR: 0x52 
P1V8_E 
2.2KΩ 
TEMP SENSOR 1 
TMP421 
ADDR: 0x98 
P3V3_STBY 
10KΩ 
I2C_CLK/DATA10(M) 
LEVEL SHIFT 
P1V8_C 
2.2KΩ 
LEVEL SHIFT 
LEVEL SHIFT 
P1V8_E 
2.2KΩ 
P1V8_E 
2.2KΩ 
LEVEL SHIFT 
P3V3_STBY 
4.7KΩ 
P3V3_STBY 
4.7KΩ 
BMC_I2C_10 
4.7KΩ 
P3V3_STBY 
I2C to GPIO 
PCA9575(HDD PRE) 
ADDR: 0x40 
HOT SWAP IC 
ADM1178 
ADDR: 0xFC 
EEPROM 
AT24C64 
ADDR: 0xA2 
P1V8_E 
2.2KΩ 
EXP_I2C_4 
PLTRST 
4.7KΩ 
P3V3 
I2C_A 
I2C_D 
I2C_E 
I2C_F 
SMBUS_CLK/DATA/ALERT4(M) 
EEPROM 
24LC64 
ADDR: 0xA0 
VOLTAGE SENSOR 
ADS1015 
ADDR: 0x92 
GBE_CLK/DATA/ALERT(M) 
10KΩ 
P3V3_STBY 
NIC_SMB 
10KΩ 
P3V3_STBY 
RTC 
PCF8563T 
ADDR: 0xA2 
2.2KΩ 
USB HUB 
USB2514B 
ADDR: 0x58 
VOLTAGE SENSOR 
ADS1015 
ADDR: 0x90 
TEMP SENSOR 2 
TMP75 
ADDR: 0x94 
TEMP SENSOR 3 
TMP75 
ADDR: 0x96 
TEMP SENSOR 4 
TMP75 
ADDR: 0x9A I2C to GPIO 
PCA9552(HDD FAULT) 
ADDR: 0xC0 
SAS REDRIVER 
PI2EQX6812 
ADDR: 0xC2 
EXP_I2C_0 
LEVEL SHIFT 
LEVEL SHIFT 
4.7KΩ 
P3V3_STBY 
Title 
Size Document Number Rev 
Date: Sheet o f 
Honey badger_LSI Base Board 1B
I2C/SMBUS DIAGRAM
A2
9 71Tuesday, January 20, 2015
Honey badger_LSI Base Board
http://www.wiwynn.com
8F, 90, Sec.1, Xintai 5th Rd., Xizhi Dist.,
New Taipei City 22102, Taiwan (R.O.C.)
Title 
Size Document Number Rev 
Date: Sheet o f 
Honey badger_LSI Base Board 1B
I2C/SMBUS DIAGRAM
A2
9 71Tuesday, January 20, 2015
Honey badger_LSI Base Board
http://www.wiwynn.com
8F, 90, Sec.1, Xintai 5th Rd., Xizhi Dist.,
New Taipei City 22102, Taiwan (R.O.C.)
Title 
Size Document Number Rev 
Date: Sheet o f 
Honey badger_LSI Base Board 1B
I2C/SMBUS DIAGRAM
A2
9 71Tuesday, January 20, 2015
Honey badger_LSI Base Board
http://www.wiwynn.com
8F, 90, Sec.1, Xintai 5th Rd., Xizhi Dist.,
New Taipei City 22102, Taiwan (R.O.C.)



5
5
4
4
3
3
2
2
1
1
D D
C C
B B
A A
Title 
Size Document Number Rev 
Date: Sheet o f 
Honey badger_LSI Base Board 1B
RESERVE
A4
10 71Tuesday, January 20, 2015
Honey badger_LSI Base Board
http://www.wiwynn.com
8F, 90, Sec.1, Xintai 5th Rd., Xizhi Dist.,
New Taipei City 22102, Taiwan (R.O.C.)
Title 
Size Document Number Rev 
Date: Sheet o f 
Honey badger_LSI Base Board 1B
RESERVE
A4
10 71Tuesday, January 20, 2015
Honey badger_LSI Base Board
http://www.wiwynn.com
8F, 90, Sec.1, Xintai 5th Rd., Xizhi Dist.,
New Taipei City 22102, Taiwan (R.O.C.)
Title 
Size Document Number Rev 
Date: Sheet o f 
Honey badger_LSI Base Board 1B
RESERVE
A4
10 71Tuesday, January 20, 2015
Honey badger_LSI Base Board
http://www.wiwynn.com
8F, 90, Sec.1, Xintai 5th Rd., Xizhi Dist.,
New Taipei City 22102, Taiwan (R.O.C.)



5
5
4
4
3
3
2
2
1
1
D D
C C
B B
A A
PCIE_SAS_CPU_RX_P0
PCIE_SAS_CPU_RX_N0PCIE_SAS_CPU_TX_N0
PCIE_SAS_CPU_TX_P0 PCIE_SAS_C_CPU_RX_P0
PCIE_SAS_C_CPU_RX_N0
CLK_100M_PCIE_N
CK_100M_EXP_SAS
CLK_100M_PCIE_P
SAS3008_RAID_TX_C_P0
SAS3008_RAID_TX_C_N0
SAS3008_RAID_TX_C_P1
SAS3008_RAID_TX_C_N1
SAS3008_RAID_TX_C_P2
SAS3008_RAID_TX_C_N2
SAS3008_RAID_TX_C_P3
SAS3008_RAID_TX_C_N3
IOC_CLK_SEL0 IOC_CLK_SEL1
CLK_100M_PCIE_P
CLK_100M_PCIE_N
IOC_CLK_SEL0
IOC_CLK_SEL1IOC_REF_CLK_N
IOC_REF_CLK_P
PCIE_SAS_CPU_TX_P1
PCIE_SAS_CPU_TX_N1
PCIE_SAS_CPU_TX_P2
PCIE_SAS_CPU_TX_N2
PCIE_SAS_CPU_TX_P3
PCIE_SAS_CPU_TX_N3
PCIE_SAS_CPU_TX_P4
PCIE_SAS_CPU_TX_N4
PCIE_SAS_CPU_TX_P5
PCIE_SAS_CPU_TX_N5
PCIE_SAS_CPU_TX_P6
PCIE_SAS_CPU_TX_N6
PCIE_SAS_CPU_TX_P7
PCIE_SAS_CPU_TX_N7
PCIE_SAS_CPU_RX_N1
PCIE_SAS_CPU_RX_P1PCIE_SAS_C_CPU_RX_P1
PCIE_SAS_C_CPU_RX_N1
PCIE_SAS_CPU_RX_N2
PCIE_SAS_CPU_RX_P2PCIE_SAS_C_CPU_RX_P2
PCIE_SAS_C_CPU_RX_N2
PCIE_SAS_CPU_RX_N3
PCIE_SAS_CPU_RX_P3PCIE_SAS_C_CPU_RX_P3
PCIE_SAS_C_CPU_RX_N3
PCIE_SAS_CPU_RX_N4
PCIE_SAS_CPU_RX_P4PCIE_SAS_C_CPU_RX_P4
PCIE_SAS_C_CPU_RX_N4
PCIE_SAS_CPU_RX_N5
PCIE_SAS_CPU_RX_P5PCIE_SAS_C_CPU_RX_P5
PCIE_SAS_C_CPU_RX_N5
PCIE_SAS_CPU_RX_N6
PCIE_SAS_CPU_RX_P6PCIE_SAS_C_CPU_RX_P6
PCIE_SAS_C_CPU_RX_N6
PCIE_SAS_CPU_RX_N7
PCIE_SAS_CPU_RX_P7PCIE_SAS_C_CPU_RX_P7
PCIE_SAS_C_CPU_RX_N7
REF_CLK IOC_REF_CLK_N
SAS3008_RAID_TX_N2
SAS3008_RAID_TX_P2
SAS3008_RAID_TX_N3
SAS3008_RAID_TX_P3
SAS3008_RAID_TX_P0
SAS3008_RAID_TX_N0
SAS3008_RAID_TX_P1
SAS3008_RAID_TX_N1
3008_SAS_RX_P1
3008_SAS_RX_N1
3008_SAS_RX_P0
3008_SAS_RX_N0
3008_SAS_RX_P3
3008_SAS_RX_N3
3008_SAS_RX_P2
3008_SAS_RX_N2
IOC_RAID_TX_N7
IOC_RAID_TX_P7SAS3008_RAID_TX_C_P7
SAS3008_RAID_TX_C_N7
IOC_RAID_TX_P5
IOC_RAID_TX_N5
SAS3008_RAID_TX_C_P5
SAS3008_RAID_TX_C_N5
IOC_RAID_TX_N6
IOC_RAID_TX_P6SAS3008_RAID_TX_C_P6
SAS3008_RAID_TX_C_N6
IOC_RAID_TX_P4
IOC_RAID_TX_N4
SAS3008_RAID_TX_C_P4
SAS3008_RAID_TX_C_N4
IOC_SAS_RX_N7
IOC_SAS_RX_P7
IOC_SAS_RX_P4
IOC_SAS_RX_N4
IOC_SAS_RX_N5
IOC_SAS_RX_P5
IOC_SAS_RX_P6
IOC_SAS_RX_N6
IOC_REF_CLK_P
P1V8_C
PCIE_SAS_CPU_RX_P0 33
PCIE_SAS_CPU_RX_N0 33
PCIE_SAS_CPU_TX_P033
PCIE_SAS_CPU_TX_N033
CLK_100M_PCIE_SAS_C_N33
CLK_100M_PCIE_SAS_C_P33
PCIE_SAS_CPU_TX_P133
PCIE_SAS_CPU_TX_N133
PCIE_SAS_CPU_TX_P233
PCIE_SAS_CPU_TX_N233
PCIE_SAS_CPU_TX_N333
PCIE_SAS_CPU_TX_P333
PCIE_SAS_CPU_TX_N433
PCIE_SAS_CPU_TX_P433
PCIE_SAS_CPU_TX_P533
PCIE_SAS_CPU_TX_N533
PCIE_SAS_CPU_TX_N633
PCIE_SAS_CPU_TX_P633
PCIE_SAS_CPU_TX_P733
PCIE_SAS_CPU_TX_N733
PCIE_SAS_CPU_RX_P1 33
PCIE_SAS_CPU_RX_N1 33
PCIE_SAS_CPU_RX_N2 33
PCIE_SAS_CPU_RX_P2 33
PCIE_SAS_CPU_RX_P3 33
PCIE_SAS_CPU_RX_N3 33
PCIE_SAS_CPU_RX_P4 33
PCIE_SAS_CPU_RX_N4 33
PCIE_SAS_CPU_RX_P5 33
PCIE_SAS_CPU_RX_N5 33
PCIE_SAS_CPU_RX_N6 33
PCIE_SAS_CPU_RX_P6 33
PCIE_SAS_CPU_RX_P7 33
PCIE_SAS_CPU_RX_N7 33
SAS3008_RAID_TX_P0 21
SAS3008_RAID_TX_N0 21
SAS3008_RAID_TX_P1 21
SAS3008_RAID_TX_N1 21
SAS3008_RAID_TX_N2 21
SAS3008_RAID_TX_P2 21
SAS3008_RAID_TX_P3 21
SAS3008_RAID_TX_N3 21
3008_SAS_RX_P021
3008_SAS_RX_N021
3008_SAS_RX_P121
3008_SAS_RX_N121
3008_SAS_RX_P221
3008_SAS_RX_N221
3008_SAS_RX_P321
3008_SAS_RX_N321
IOC_RAID_TX_P7 34
IOC_RAID_TX_N7 34
IOC_RAID_TX_N5 34
IOC_RAID_TX_P5 34
IOC_RAID_TX_N6 34
IOC_RAID_TX_P6 34
IOC_RAID_TX_N4 34
IOC_RAID_TX_P4 34
IOC_SAS_RX_P734
IOC_SAS_RX_N734
IOC_SAS_RX_P434
IOC_SAS_RX_N434
IOC_SAS_RX_P534
IOC_SAS_RX_N534
IOC_SAS_RX_N634
IOC_SAS_RX_P634
Title 
Size Document Number R e v 
Date: Sheet 
o f 
Honey badger_LSI Base Board 1B
SAS3008_PCIE & SAS
A3
11 71Tuesday, January 20, 2015
Honey badger_LSI Base Board
http://www.wiwynn.com
8F, 90, Sec.1, Xintai 5th Rd., Xizhi Dist.,
New Taipei City 22102, Taiwan (R.O.C.)
Title 
Size Document Number R e v 
Date: Sheet 
o f 
Honey badger_LSI Base Board 1B
SAS3008_PCIE & SAS
A3
11 71Tuesday, January 20, 2015
Honey badger_LSI Base Board
http://www.wiwynn.com
8F, 90, Sec.1, Xintai 5th Rd., Xizhi Dist.,
New Taipei City 22102, Taiwan (R.O.C.)
Title 
Size Document Number R e v 
Date: Sheet 
o f 
Honey badger_LSI Base Board 1B
SAS3008_PCIE & SAS
A3
11 71Tuesday, January 20, 2015
Honey badger_LSI Base Board
http://www.wiwynn.com
8F, 90, Sec.1, Xintai 5th Rd., Xizhi Dist.,
New Taipei City 22102, Taiwan (R.O.C.)
SC862 SCD22U6D3V1MX-1-GP1 2
SC884 SCD01U10V1KX-GP1 2
SR582
51R2F-2-GP
1 2
SR583
10KR2F-2-GP
12
SC863 SCD22U6D3V1MX-1-GP1 2
SC893 SCD01U10V1KX-GP1 2
SC885 SCD01U10V1KX-GP1 2
SC882 SCD01U10V1KX-GP1 2
SC873 SCD22U6D3V1MX-1-GP1 2
SC895 SCD01U10V1KX-GP1 2
SC887
SC12P50V2JN-3GP
1 2
SX1
XTAL-25MHZ-105-GP
4 1
23
SC880 SCD01U10V1KX-GP1 2
SC901 SCD01U10V1KX-GP1 2
SC878 SCD01U10V1KX-GP1 2
SR581 0R2J-2-GP1 2
SC892 SCD01U10V1KX-GP1 2
SC883 SCD01U10V1KX-GP1 2
SC870 SCD22U6D3V1MX-1-GP1 2
SR586
51R2F-2-GP
1 2
SR922
0R2J-2-GP
1 2
SC868 SCD22U6D3V1MX-1-GP1 2
SC879 SCD01U10V1KX-GP1 2
1 OF 14 SU2A
SAS3008C0-1-DB-500020657-1-GP
PCE_REF_CLKAK4
PCE_REF_CLK#AK5
PCE_RX0AK7
PCE_RXN0AJ7
PCE_RX1AK8
PCE_RXN1AJ8
PCE_RX2AK10
PCE_RXN2AJ10
PCE_RX3AK11
PCE_RXN3AJ11
PCE_RX4AK13
PCE_RXN4AJ13
PCE_RX5AK14
PCE_RXN5AJ14
PCE_RX6AK16
PCE_RXN6AJ16
PCE_RX7AK17
PCE_RXN7AJ17
PCE_RST_OUT# AJ19
PCE_TX0 AG7
PCE_TXN0 AF7
PCE_TX1 AG8
PCE_TXN1 AF8
PCE_TX2 AG10
PCE_TXN2 AF10
PCE_TX3 AG11
PCE_TXN3 AF11
PCE_TX4 AG13
PCE_TXN4 AF13
PCE_TX5 AG14
PCE_TXN5 AF14
PCE_TX6 AG16
PCE_TXN6 AF16
PCE_TX7 AG17
PCE_TXN7 AF17
SC866 SCD22U6D3V1MX-1-GP1 2
SC876 SCD22U6D3V1MX-1-GP1 2
SC864 SCD22U6D3V1MX-1-GP1 2
SR584
10KR2F-2-GP
12
SC891 SCD01U10V1KX-GP1 2
SC902 SCD01U10V1KX-GP1 2
SC877 SCD01U16V2KX-3GP1 2
SC871 SCD22U6D3V1MX-1-GP1 2
SC861 SCD22U6D3V1MX-1-GP1 2
SR587
10KR2F-2-GP
NOPOP
12
SC874 SCD22U6D3V1MX-1-GP1 2
SC881 SCD01U10V1KX-GP1 2
SC875 SCD22U6D3V1MX-1-GP1 2
SC872 SCD22U6D3V1MX-1-GP1 2
2 OF 14 SU2B
SAS3008C0-1-DB-500020657-1-GP
SAS_REF_CLKP1
SAS_REF_CLK#P2
SAS_RX0AH4
SAS_RXN0AH5
SAS_RX1AG4
SAS_RXN1AG5
SAS_RX2AE4
SAS_RXN2AE5
SAS_RX3AD4
SAS_RXN3AD5
SAS_RX4AB4
SAS_RXN4AB5
SAS_RX5AA4
SAS_RXN5AA5
SAS_RX6W4
SAS_RXN6W5
SAS_RX7V4
SAS_RXN7V5
SAS_CLK_SEL0 P29
SAS_CLK_SEL1 T28
SAS_TX0 AH1
SAS_TXN0 AH2
SAS_TX1 AG1
SAS_TXN1 AG2
SAS_TX2 AE1
SAS_TXN2 AE2
SAS_TX3 AD1
SAS_TXN3 AD2
SAS_TX4 AB1
SAS_TXN4 AB2
SAS_TX5 AA1
SAS_TXN5 AA2
SAS_TX6 W1
SAS_TXN6 W2
SAS_TX7 V1
SAS_TXN7 V2
SC890 SCD01U10V1KX-GP1 2
SR588 0R2J-2-GP1 2
SC894 SCD01U10V1KX-GP1 2
SR921
10KR2F-2-GP
NOPOP
12
SR585 51R2F-2-GP12
SC1296 SCD22U6D3V1MX-1-GP1 2
SC869 SCD22U6D3V1MX-1-GP1 2
SC886
SC12P50V2JN-3GP
1 2
SC865 SCD22U6D3V1MX-1-GP1 2



5
5
4
4
3
3
2
2
1
1
D D
C C
B B
A A
USB 
Ethernet 
ADD=1010000 (0xA0) 
IOC_EEPROM 1mA 
SBL_SDA
IOC_SDA_3
IOC_SCL_3
SBL_SCL
IOC_SDA_4
IOC_SCL_4
IOC_SDA_0
IOC_SCL_0
IOC_SDA_1
IOC_SCL_1
IOC_SDA_2
IOC_SCL_2
SIO_DIN_1
SIO_CLK_1
SIO_LOAD_1
SIO_DOUT_1
SIO_DIN_0
SIO_CLK_0
SIO_LOAD_0
SIO_DOUT_0
SBL_SDAIOC_EEPROM_SDA
IOC_EEPROM_WP
IOC_EEPROM_A0
SBL_SCL
IOC_EEPROM_A1
IOC_EEPROM_A2
IOC_EEPROM_SCL
IOC_SCL_2
IOC_SDA_2
IOC_SCL_3
IOC_SDA_3
IOC_SDA_4
IOC_SCL_4
IOC_GPIO_20
IOC_GPIO_0
IOC_GPIO_21
SBL_SDA
SBL_SCL
IOC_GPIO_22
IOC_GPIO_23
IOC_GPIO_24
IOC_GPIO_25
IOC_GPIO_26
IOC_GPIO_27
IOC_GPIO_28
IOC_GPIO_29
IOC_GPIO_30
IOC_GPIO_31
IOC_GPIO_32
IOC_GPIO_33
IOC_GPIO_34
IOC_GPIO_35
IOC_GPIO_36
IOC_GPIO_37
IOC_GPIO_38
IOC_GPIO_39
IOC_SDA_0
IOC_SCL_0
SIO_CLK_0
IOC_GPIO_1
IOC_GPIO_2
IOC_GPIO_3
IOC_SDA_1
IOC_SCL_1
IOC_GPIO_4
IOC_GPIO_5
IOC_GPIO_6
IOC_GPIO_7
IOC_GPIO_8
IOC_GPIO_9
IOC_GPIO_10
IOC_GPIO_11
IOC_GPIO_12
IOC_GPIO_13
IOC_GPIO_14
IOC_GPIO_15
IOC_GPIO_16
SIO_DIN_0
SIO_DOUT_0
SIO_LOAD_0
SIO_CLK_1
SIO_DIN_1
SIO_DOUT_1
SIO_LOAD_1
IOC_GPIO_17
IOC_GPIO_18
IOC_GPIO_19
IOC_SIO_BLINK
P1V8_C
P1V8_C
P1V8_C
IOC_SDA_418
IOC_SCL_418
Title 
Size Document Number R e v 
Date: Sheet 
o f 
Honey badger_LSI Base Board 1B
SAS3008_GPIO&USB&ETH
A3
12 71Tuesday, January 20, 2015
Honey badger_LSI Base Board
http://www.wiwynn.com
8F, 90, Sec.1, Xintai 5th Rd., Xizhi Dist.,
New Taipei City 22102, Taiwan (R.O.C.)
Title 
Size Document Number R e v 
Date: Sheet 
o f 
Honey badger_LSI Base Board 1B
SAS3008_GPIO&USB&ETH
A3
12 71Tuesday, January 20, 2015
Honey badger_LSI Base Board
http://www.wiwynn.com
8F, 90, Sec.1, Xintai 5th Rd., Xizhi Dist.,
New Taipei City 22102, Taiwan (R.O.C.)
Title 
Size Document Number R e v 
Date: Sheet 
o f 
Honey badger_LSI Base Board 1B
SAS3008_GPIO&USB&ETH
A3
12 71Tuesday, January 20, 2015
Honey badger_LSI Base Board
http://www.wiwynn.com
8F, 90, Sec.1, Xintai 5th Rd., Xizhi Dist.,
New Taipei City 22102, Taiwan (R.O.C.)
SR617 2K2R2F-GP1 2
STP1331
SR618 2K2R2F-GP1 2
STP41
STP471
SR621 2K2R2F-GP1 2
SR628 2K2R2F-GP1 2
SR632 2K2R2F-GP1 2
4 OF 14 SU2D
SAS3008C0-1-DB-500020657-1-GP
ULPI0_DATA0D3
ULPI0_DATA1A2
ULPI0_DATA2C2
ULPI0_DATA3C3
ULPI0_DATA4P5
ULPI0_DATA5P6
ULPI0_DATA6F2
ULPI0_DATA7E2
ULPI0_CLKE3
ULPI0_DIRR7
ULPI0_NXTB2
ULPI0_STPN6
ENET_RXD0L3
ENET_RXD1H3
ENET_RXD2H6
ENET_RXD3K6
ENET_RXD4F9
ENET_RXD5F10
ENET_RXD6F3
ENET_RXD7F7
ENET_COLD1
ENET_CRSJ3
ENET_IN_CLKB5
ENET_MDINT#C1
ENET_RXCLKH1
ENET_RXDVJ6
ENET_RXERJ2
ULPI1_DATA0 B10
ULPI1_DATA1 N5
ULPI1_DATA2 B4
ULPI1_DATA3 A5
ULPI1_DATA4 A3
ULPI1_DATA5 C4
ULPI1_DATA6 B3
ULPI1_DATA7 B1
ULPI1_CLK A4
ULPI1_DIR B6
ULPI1_NXT C5
ULPI1_STP A7
ENET_TXD0 G6
ENET_TXD1 G3
ENET_TXD2 F1
ENET_TXD3 G2
ENET_TXD4 F6
ENET_TXD5 F8
ENET_TXD6 C9
ENET_TXD7 C10
ENET_GTXCLK J1
ENET_MDC H2
ENET_MDIO D2
ENET_TXCLK K3
ENET_TXEN E1
ENET_TXER G1
3 OF 14 SU2C
SAS3008C0-1-DB-500020657-1-GP
SBL_SCLT30
SBL_SDAN30
IIC0_SCLV29
IIC0_SDAR29
IIC1_SCLP30
IIC1_SDAV30
IIC2_SCLV28
IIC2_SDAY28
IIC3_SCLP28
IIC3_SDAU29
IIC4_SCLW29
IIC4_SDAR28
SIO0_CLKM1
SIO0_DINT6
SIO0_DOUTK2
SIO0_LOADM3
SIO1_CLKL1
SIO1_DINL2
SIO1_DOUTM2
SIO1_LOADK1
SIO_BLINKR5
GPIO0 AF29
GPIO1 AJ26
GPIO2 AH22
GPIO3 AH23
GPIO4 AJ30
GPIO5 AH24
GPIO6 AH25
GPIO7 AE21
GPIO8 AC30
GPIO9 AK29
GPIO10 AH28
GPIO11 AH30
GPIO12 AJ29
GPIO13 AJ25
GPIO14 AJ27
GPIO15 Y30
GPIO16 AF30
GPIO17 AD30
GPIO18 AG29
GPIO19 AK28
GPIO20 AJ28
GPIO21 AG30
GPIO22 AH29
GPIO23 AB29
GPIO24 W30
GPIO25 AG28
GPIO26 AF28
GPIO27 AD29
GPIO28 AC28
GPIO29 AD28
GPIO30 AC29
GPIO31 AE30
GPIO32 N28
GPIO33 AA29
GPIO34 AB28
GPIO35 AB30
GPIO36 AA28
GPIO37 AA30
GPIO38 W28
GPIO39 AE29
STP18 1
STP1421
SR619 2K2R2F-GP1 2
STP1401
STP911
STP151 STP131
STP241
STP251
STP7 1
SR620 2K2R2F-GP1 2
SR631 2K2R2F-GP1 2
SR627 2K2R2F-GP1 2
STP1381
SR616 2K2R2F-GP1 2
STP9 1
STP1391
SR720 
4K7R2F-GP 
1 2
STP931
STP941
STP1321
SR614 2K2R2F-GP1 2
STP5 1
SR625 2K2R2F-GP1 2
SR629 2K2R2F-GP1 2
SR615 2K2R2F-GP1 2
SR723
0R2J-2-GP
1 2
SR605 
10KR2F-2-GP 
1 2
SR622 2K2R2F-GP1 2
STP111
STP461
SR718
0R2J-2-GP
1 2
SR721 
4K7R2F-GP 
1 2
STP1351
STP21
STP191
STP101
STP14 1
STP1311
SC1064 
SCD1U16V2KX-3GP 
1 2
STP771
SR722
0R2J-2-GP
1 2
SR630 2K2R2F-GP1 2
STP1361
STP3 1
STP201
STP21 1
STP1371
STP61
SR623 2K2R2F-GP1 2
STP441
STP12 1
STP81
SU61
AT24C64D-SSHM-T-GP
A01
A12
A23
GND4
VCC 8
WP 7
SCL 6
SDA 5
SR626 2K2R2F-GP1 2
SR717 
4K7R2F-GP 
NOPOP
1 2
STP16 1
STP1341
STP221
STP1411
SR633 2K2R2F-GP1 2
STP1301
SR624 2K2R2F-GP1 2
STP11
STP781
SR719 
4K7R2F-GP 
1 2
STP921
STP171
STP451
STP231
STP761
SC1065 
SCD01U50V2KX-1GP 
1 2



5
5
4
4
3
3
2
2
1
1
D D
C C
B B
A A
Low Vth=1V Low Vth=1V 
AVSO_IDDTN18
SYS_RST_N_0
SYS_RST_N_1
SYS_CORE_TRI#
POWERLOSS#
CP_DONE
MEM_CLK_SEL
RTRIM#
RTRIM
SYS_HB_LED
SYS_ERR_0
SYS_DBMODE0
SYS_DBMODE1
SYS_DBMODE2
SYS_DBMODE3
SYS_DBMODE4
LSI_JTAG_EN_N
LSI_SCAN_EN
LSI_TN
LSI_IDDT
CP_DONE
SYS_CORE_TRI#
POWERLOSS#
SYS_RST_N_1
LSI_TN
SYS_DBMODE1
SYS_DBMODE2
SYS_DBMODE3
LSI_IDDT
SYS_DBMODE4
SYS_DBMODE0
LSI_JTAG_EN_N
LSI_SCAN_EN
JTAG_IOC_TCK
JTAG_IOC_TMS
JTAG_IOC_TDI
IOC_TRST_N
ICE0_TCK
ICE0_TMS
ICE0_TDI
ICE0_TDO
ICE0_TRST#
ICE_SEL
ICE1_TCK
ICE1_TMS
ICE1_TDI
ICE1_TDO
ICE1_TRST#
SYS_HALT0#
SYS_HALT1#
ICE1_TCK
ICE1_TMS
ICE1_TDI
ICE1_TRST#
ICE0_TRST#
SYS_HALT1#
ICE0_TDI
ICE0_TCK
ICE0_TMS
ICE_SEL
SYS_HB_LED_D
SYS_HB_LED_R
SYS_ERR_0
SYS_ERROR_LED_D
SYS_ERROR_LED_R
SPARE0
SPARE1
SPARE2
SPARE3
SPARE4
SPARE5
IOC_UART_1_RX
IOC_UART_1_TX
UART_SERCLK
UART_SERCLK
IOC_UART_1_RX
IOC_UART_0_RX
OSC_REF_CLK
IOC_RESET#
IOC_RESET#
IOC_VREF_SET
SYS_HALT0#
IOC_TRST_N
IOC_UART_0_RX
IOC_UART_0_TX
SYS_ERROR1
SYS_RST
IOC_TDO
P3V3_STBY_B
PMU_PLTRST_R_N
P3V3_STBY_R
IOC_TDO
JTAG_IOC_TCK
JTAG_IOC_TMS
JTAG_IOC_TDI
IOC_TRST_N SYS_HB_LED
P1V8_C
P1V8_C
P1V8_C
P3V3 P3V3
P1V8_C
P1V8_C
P1V8_STBY
P1V8_C
P3V3_STBY
P1V8_C
P1V8_C_PG61,65
PWRGD_P0V955_C63
IOC_UART_0_RX 18
IOC_UART_0_TX 18
AVSO_VREF63
JTAG_EXP_IOC_RST 25,36
JTAG_EXP_IOC_TCK 25,36
JTAG_IOC_TDO 36
JTAG_IOC_L_TDI 36
JTAG_EXP_IOC_TMS 25,36
SYS_RST_N_0 18
PMU_PLTRST_N18,31,33,40,42,44,50,52
Title 
Size Document Number R e v 
Date: Sheet 
o f 
Honey badger_LSI Base Board 1B
SAS3008_MISC
A3
13 71Tuesday, January 20, 2015
Honey badger_LSI Base Board
http://www.wiwynn.com
8F, 90, Sec.1, Xintai 5th Rd., Xizhi Dist.,
New Taipei City 22102, Taiwan (R.O.C.)
Title 
Size Document Number R e v 
Date: Sheet 
o f 
Honey badger_LSI Base Board 1B
SAS3008_MISC
A3
13 71Tuesday, January 20, 2015
Honey badger_LSI Base Board
http://www.wiwynn.com
8F, 90, Sec.1, Xintai 5th Rd., Xizhi Dist.,
New Taipei City 22102, Taiwan (R.O.C.)
Title 
Size Document Number R e v 
Date: Sheet 
o f 
Honey badger_LSI Base Board 1B
SAS3008_MISC
A3
13 71Tuesday, January 20, 2015
Honey badger_LSI Base Board
http://www.wiwynn.com
8F, 90, Sec.1, Xintai 5th Rd., Xizhi Dist.,
New Taipei City 22102, Taiwan (R.O.C.)
SR668 
10KR2F-2-GP 
1 2
STP52 1
SR924 0R2J-2-GP1 2
SR681 
10KR2F-2-GP 
1 2
SR648
4K7R2F-GP
1 2
SR651 
150R2F-1-GP 
1 2
SR666 
10KR2F-2-GP 
1 2
STP381
SQ4
2N7002A-7-GP
G
SD
STP361
STP591
SR665 
10KR2F-2-GP 
NOPOP
1 2
SQ3
2N7002A-7-GP
G
SD
SR680 
4K7R2F-GP 
1 2
SR672 
4K7R2F-GP 
1 2
SR684 
10KR2F-2-GP 
1 2
STP411
SR667 
10KR2F-2-GP 
1 2
STP371
SR660
4K7R2F-GP
12
STP291
SR643 
4K7R2F-GP 
1 2
STP261
SR658 
4K7R2F-GP 
NOPOP1 2
STP391
SR661 
10KR2F-2-GP 
1 2
SR676 
4K7R2F-GP 
1 2
SR863 0R2J-2-GP1 2
SR682 
10KR2F-2-GP 
1 2
STP42 1
STP351
STP271
SR657
10KR2F-2-GP
1 2
SR864 0R2J-2-GP1 2
SR865 0R2J-2-GP1 2
SR650 3KR2J-2-GP1 2
STP311
SR645 
4K7R2F-GP 
1 2
SR674 
4K7R2F-GP 
1 2
SR647 
4K7R2F-GP 
1 2
SR686 
10KR2F-2-GP 
1 2
STP341
SR685 
10KR2F-2-GP 
1 2
SQ1
AO3400A-GP
G
D S
SR656
0R2J-2-GP
12
STP301
STP581
SR669 
10KR2F-2-GP 
1 2
SR664 
10KR2F-2-GP 
NOPOP
1 2
SR688 
4K7R2F-GP 
1 2
STP54 1
STP491
STP281
STP331
SR655
4K7R2F-GP
1 2
SR652 
150R2F-1-GP 
1 2
SQ2
AO3400A-GP
G
D S
SR679 
4K7R2F-GP 
1 2
SR687 
10KR2F-2-GP 
1 2
SR683 
10KR2F-2-GP 
1 2
STP401
SR649
10KR2F-2-GP
1 2
STP51 1
SR670 
4K7R2F-GP 
1 2
STP115 1
SR677 
4K7R2F-GP 
1 2
SR675 
4K7R2F-GP 
1 2
STP481
STP611
SR662 
10KR2F-2-GP 
NOPOP
1 2
STP55 1
SLED25
LED-YG-51-GP
A K
STP601
SR642
10KR2F-2-GP
1 2
STP50 1
SR653
10KR2F-2-GP
1 2
SR663 
10KR2F-2-GP 
NOPOP
1 2
STP53 1
SR671 
4K7R2F-GP 
1 2
SU57
TPS3808G18DRVT-GP-U
VDD1
SENSE2
CT3
MR# 4GND 5RESET# 6GND 7
SLED26
LED-YG-51-GP
A K
SR659 
10KR2F-2-GP 
1 2
STP321
STP43 1
SR654
4K7R2F-GP
1 2
SR678 
4K7R2F-GP 
1 2
SR673 
4K7R2F-GP 
1 2
6 OF 14 SU2F
SAS3008C0-1-DB-500020657-1-GP
AVSO_VREFB13
AVSO_IDDTN18B12
AVSO_PGIO18C12
AVSO_PGCORE18A13
PG_COREA12
VREF_SETB9
SYS_PWR_ON_RST#AJ21
SYS_RST0#AH20
SYS_RST1#AE23
MSS_PWR_ON_RST#U28
SYS_CORE_TRI#R30
POWERLOSS#R6
CP_DONEU30
MEM_CLK_SELN29
SYS_RTRIMT1
SYS_RTRIM#T2
SYS_HB_LEDT29
SYS_ERROR0AJ20
SYS_ERROR1AK22
SYS_DBMODE0AE22
SYS_DBMODE1AK20
SYS_DBMODE2AK24
SYS_DBMODE3AJ23
SYS_DBMODE4AK21
SYSTEM_JTAG_ENABLE#B16
LSI_SCAN_ENABLEB17
LSI_TNC16
LSI_IDDTA18
SPARE0AH27
SPARE1AK25
SPARE2AJ22
SPARE3AE20
SPARE4Y29
SPARE5AE19
UART0_RX AJ24
UART0_TX AK27
UART1_RX AH26
UART1_TX AH21
UART_SERCLK AE28
ICE_SEL M6
ICE0_TCK A9
ICE0_TMS C7
ICE0_TDI B8
ICE0_TDO C8
ICE0_TRST# A8
ICE1_TCK B7
ICE1_TMS A6
ICE1_TDI L6
ICE1_TDO A10
ICE1_TRST# C6
SYS_HALT0# AK23
SYS_HALT1# AK26
LSI_TCK C17
LSI_TMS B18
LSI_TDI A17
LSI_TDO C18
LSI_TRST# A16
OSC_OUT_REF_CLK T4
TST_VREFPSENSE C13
NC#AH19 AH19
NC#AK19 AK19
SR866 0R2J-2-GP1 2



5
5
4
4
3
3
2
2
1
1
D D
C C
B B
A A
XM_ADDR_10
XM_ADDR_12
XM_ADDR_13
XM_ADDR_3
XM_DATA_0
XM_ADDR_21
XM_ADDR_14
XM_ADDR_25
XM_ADDR_15
XM_ADDR_16
XM_ADDR_24
XM_ADDR_20
XM_ADDR_17
XM_ADDR_18
XM_ADDR_19
XM_ADDR_0
XM_ADDR_1
XM_ADDR_2
XM_ADDR_4
XM_ADDR_5
XM_ADDR_6
XM_ADDR_9
XM_ADDR_8
XM_ADDR_11
XM_ADDR_7
XM_ADDR_22
XM_ADDR_23
XM_DATA_1
XM_DATA_2
XM_DATA_3
XM_DATA_4
XM_DATA_5
XM_DATA_6
XM_DATA_7
XM_DATA_8
XM_DATA_9
XM_DATA_10
XM_DATA_11
XM_DATA_12
XM_DATA_13
XM_DATA_14
XM_DATA_15
XM_ALE
XM_CLE
XM_WP
XM_RB
XM_OE_N
XM_F_RST_N
XM_NOR_CS_N
XM_NAND_CS_N
XM_ADDR_16
XM_ADDR_17
XM_ADDR_18
XM_ADDR_19
XM_ADDR_20
XM_ADDR_21
XM_CS0_N
XM_DATA_0
XM_DATA_1
XM_DATA_2
XM_DATA_3
XM_DATA_15
XM_DATA_11
XM_DATA_12
XM_DATA_13
XM_DATA_14
XM_DATA_4
XM_DATA_5
XM_DATA_6
XM_DATA_7
XM_DATA_8
XM_DATA_9
XM_DATA_10
XM_F_RST_N
XM_ADDR_1
XM_ADDR_5
XM_ADDR_6
XM_ADDR_7
XM_ADDR_8
XM_ADDR_13
XM_ADDR_14
XM_ADDR_15
XM_ADDR_16
XM_ADDR_9
XM_ADDR_10
XM_ADDR_11
XM_ADDR_12
XM_ADDR_21
XM_ADDR_22
XM_ADDR_23
XM_ADDR_17
XM_ADDR_18
XM_ADDR_19
XM_ADDR_20
XM_ADDR_3
XM_ADDR_4
XM_ADDR_2
XM_OE_N
XM_WE_N
IOC_WP_N
XM_ADDR_24
XM_ADDR_25
XM_NOR_CS_N
XM_WE_N
XM_RB
P1V8_C
P1V8_C
P1V8_C
P1V8_C
P1V8_C
P3V3P1V8_C
P1V8_C
P1V8_C
Title 
Size Document Number R e v 
Date: Sheet 
o f 
Honey badger_LSI Base Board 1B
SAS3008_FLASH
A3
14 71Tuesday, January 20, 2015
Honey badger_LSI Base Board
http://www.wiwynn.com
8F, 90, Sec.1, Xintai 5th Rd., Xizhi Dist.,
New Taipei City 22102, Taiwan (R.O.C.)
Title 
Size Document Number R e v 
Date: Sheet 
o f 
Honey badger_LSI Base Board 1B
SAS3008_FLASH
A3
14 71Tuesday, January 20, 2015
Honey badger_LSI Base Board
http://www.wiwynn.com
8F, 90, Sec.1, Xintai 5th Rd., Xizhi Dist.,
New Taipei City 22102, Taiwan (R.O.C.)
Title 
Size Document Number R e v 
Date: Sheet 
o f 
Honey badger_LSI Base Board 1B
SAS3008_FLASH
A3
14 71Tuesday, January 20, 2015
Honey badger_LSI Base Board
http://www.wiwynn.com
8F, 90, Sec.1, Xintai 5th Rd., Xizhi Dist.,
New Taipei City 22102, Taiwan (R.O.C.)
SR702
10KR2F-2-GP
1 2
SR692
10KR2F-2-GP
1 2
SC914 
SCD1U16V2KX-3GP 
1 2
STP158 1
SR708
10KR2F-2-GP
1 2
STP151 1
STP152 1
STP161 1
SR706
10KR2F-2-GP
1 2
SR690
10KR2F-2-GP
1 2
SR703
10KR2F-2-GP
1 2
SR705
10KR2F-2-GP
1 2
SR700
10KR2F-2-GP
1 2
STP118 1
STP160 1
SR732
10KR2F-2-GP
1 2
SR689
10KR2F-2-GP
1 2
SR697
10KR2F-2-GP
1 2
SU58
S29GL128S10TFIV20-GP
NC#55 55
VSS 52
VCC43
VSS 33
VIO29
A031
A126
A225
A324
A423
A522
A621
A720
A810
A99
A108
A117
A126
A135
A144
A153
A1654
A1719
A1818
A1911
A2012
A2115
A222
NC#1 1
NC#56 56
DQ0 35
DQ1 37
DQ2 39
DQ3 41
DQ4 44
DQ5 46
DQ6 48
DQ7 50
DQ8 36
DQ9 38
DQ10 40
DQ11 42
DQ12 45
DQ13 47
DQ14 49
DQ15 51
DNU 28
RFU#27 27
RFU#30 30
RFU#53 53
OE#34
CE#32
WE#13
WP#16
RESET# 14
RY/BY# 17
5 OF 14 SU2E
SAS3008C0-1-DB-500020657-1-GP
XM_ADDR0B25
XM_ADDR1B27
XM_ADDR2C27
XM_ADDR3A26
XM_ADDR4A28
XM_ADDR5C28
XM_ADDR6B28
XM_ADDR7B30
XM_ADDR8B29
XM_ADDR9D28
XM_ADDR10D29
XM_ADDR11C29
XM_ADDR12E28
XM_ADDR13C30
XM_ADDR14E30
XM_ADDR15G28
XM_ADDR16F29
XM_ADDR17D30
XM_ADDR18H30
XM_ADDR19F28
XM_ADDR20F30
XM_ADDR21G29
XM_ADDR22J29
XM_ADDR23K29
XM_ADDR24J30
XM_ADDR25H29
XM_ALEB26
XM_CLEC23
XM_WPA25
XM_RBA22
XM_DATA0 H28
XM_DATA1 K30
XM_DATA2 K28
XM_DATA3 L30
XM_DATA4 L29
XM_DATA5 C22
XM_DATA6 C20
XM_DATA7 C24
XM_DATA8 C21
XM_DATA9 C26
XM_DATA10 C25
XM_DATA11 A29
XM_DATA12 J28
XM_DATA13 G30
XM_DATA14 E29
XM_DATA15 C19
XM_OE# B22
XM_WE# A24
XM_WBE0# B24
XM_WBE1# A27
XM_F_RST# B20
XM_CS0# B19
XM_CS1# A23
XM_CS2# B23
XM_CS3# A19
XM_NOR_CS# A21
XM_NAND_CS# B21
EXT_GPIO_LATCH# A20
STP119 1
STP120 1
SR694
10KR2F-2-GP1 2
SR695
10KR2F-2-GP
NOPOP
1 2
SR693
10KR2F-2-GP
1 2
SR698
10KR2F-2-GP
NOPOP
1 2
SR696
10KR2F-2-GP
1 2
SC1099 
SCD1U16V2KX-3GP 
1 2
STP159 1
STP153 1
STP117 1STP116 1
STP121 1
SR701
10KR2F-2-GP
1 2
SR699
10KR2F-2-GP
1 2
SR691
10KR2F-2-GP
1 2



5
5
4
4
3
3
2
2
1
1
D D
C C
B B
A A
PCE_VDDH
SAS0_VDDH
HM40ADC_VDDA
PLL_VDD
VDDA_SAS_REF_CLK
SHELL_PLL_VDD
VDDIO_15
SYS_PLL_VDD
P1V8_C
P1V8_CP1V8_C
P1V8_C P1V8_C
P1V5_C
P1V8_C
HM40ADC_VDDA
PLL_VDD
SHELL_PLL_VDD
SYS_PLL_VDD
VDDA_SAS_REF_CLK
SAS0_VDDH
PCE_VDDH
P1V8_C
Title 
Size Document Number R e v 
Date: Sheet 
o f 
Honey badger_LSI Base Board 1B
SAS3008_POWER_1
A3
15 71Tuesday, January 20, 2015
Honey badger_LSI Base Board
http://www.wiwynn.com
8F, 90, Sec.1, Xintai 5th Rd., Xizhi Dist.,
New Taipei City 22102, Taiwan (R.O.C.)
Title 
Size Document Number R e v 
Date: Sheet 
o f 
Honey badger_LSI Base Board 1B
SAS3008_POWER_1
A3
15 71Tuesday, January 20, 2015
Honey badger_LSI Base Board
http://www.wiwynn.com
8F, 90, Sec.1, Xintai 5th Rd., Xizhi Dist.,
New Taipei City 22102, Taiwan (R.O.C.)
Title 
Size Document Number R e v 
Date: Sheet 
o f 
Honey badger_LSI Base Board 1B
SAS3008_POWER_1
A3
15 71Tuesday, January 20, 2015
Honey badger_LSI Base Board
http://www.wiwynn.com
8F, 90, Sec.1, Xintai 5th Rd., Xizhi Dist.,
New Taipei City 22102, Taiwan (R.O.C.)
SR713
10R2F-L-GP
1 2
SC942 
SCD1U6D3V1KX-GP 
1 2
SL2
MPZ2012S601AT-GP
12
SC936 
SC10U6D3V5KX-4GP 
1 2
SR710
10R2F-L-GP
1 2
SC939 
SCD1U6D3V1KX-GP 
1 2
SC943 
SCD1U6D3V1KX-GP 
1 2
SL4
MPZ2012S601AT-GP
12
SC921 
SC1U6D3V1MX-GP 
1 2
SC915 
SC22U6D3V5MX-2GP 
1 2
7 OF 14 SU2G
SAS3008C0-1-DB-500020657-1-GP
VDDIO_TOPD16
VDDIO_TOPD18
VDDIO_TOPD20
VDDIO_TOPD22
VDDIO_TOPD24
VDDIO_TOPD26
VDDIO_TOPE15
VDDIO_TOPE17
VDDIO_TOPE19
VDDIO_TOPE21
VDDIO_RGT_1D4
VDDIO_RGT_1D6
VDDIO_RGT_1D8
VDDIO_RGT_1D10
VDDIO_RGT_1E5
VDDIO_RGT_1E7
VDDIO_RGT_1E9
VDDIO_RGT_1F4
VDDIO_BOT_1N27
VDDIO_BOT_1P26
VDDIO_BOT_1R27
VDDIO_BOT_1T26
VDDIO_BOT_1U27
VDDIO_BOT_1V26
VDDIO_BOT_1W27
VDDIO_BOT_1Y26
VDDIO_BOT_1AA27
VDDIO_BOT_1AB26
VDDIO_BOT_1AC27
AVSO_VDDA18M9
HM40ADC_VDDAA14
PLL_VDDAA23
SHELL_PLL_VDDU10
SYS_PLL_VDDT9
VDDA_SAS_REF_CLKV11
SAS0_VDDHU1
SAS0_VDDHY1
SAS0_VDDHY6
SAS0_VDDHAC1
SAS0_VDDHAC6
SAS0_VDDHAF1
SAS0_VDDHAJ1
VDDIO_TOP E23
VDDIO_TOP E25
VDDIO_TOP E27
VDDIO_TOP F26
VDDIO_TOP G27
VDDIO_TOP H26
VDDIO_TOP J27
VDDIO_TOP K26
VDDIO_TOP L27
VDDIO_RGT_1 G5
VDDIO_RGT_1 H4
VDDIO_RGT_1 J5
VDDIO_RGT_1 K4
VDDIO_RGT_1 L5
VDDIO_RGT_1 M4
VDDIO_RGT_1 N3
VDDIO_RGT_1 P4
VDDIO_BOT_1 AD26
VDDIO_BOT_1 AE27
VDDIO_BOT_1 AF20
VDDIO_BOT_1 AF22
VDDIO_BOT_1 AF24
VDDIO_BOT_1 AF26
VDDIO_BOT_1 AG19
VDDIO_BOT_1 AG21
VDDIO_BOT_1 AG23
VDDIO_BOT_1 AG25
VDDIO_BOT_1 AG27
VDDIO_15 L22
PCE_VDDH AE8
PCE_VDDH AE10
PCE_VDDH AE12
PCE_VDDH AE14
PCE_VDDH AE16
PCE_VDDH AG9
PCE_VDDH AG12
PCE_VDDH AG18
PCE_VDDH AH15
SC944 
SCD1U6D3V1KX-GP 
1 2
SC938 
SCD1U6D3V1KX-GP 
1 2
SC941 
SC1U6D3V1MX-GP 
1 2
SC920 
SC10U6D3V5KX-4GP 
1 2
SR711
10R2F-L-GP
1 2
SC930 
SCD1U6D3V1KX-GP 
1 2
SC940 
SCD1U6D3V1KX-GP 
1 2
SC937 
SC1U6D3V1MX-GP 
1 2
SC926 
SCD1U6D3V1KX-GP 
1 2
SR714
10R2F-L-GP
1 2
SC929 
SC1U6D3V1MX-GP 
1 2
SC923 
SC22U6D3V5MX-2GP 
1 2
SC916 
SC10U6D3V5KX-4GP 
1 2
SL5
MPZ2012S601AT-GP
12
SC931 
SC22U6D3V5MX-2GP 
1 2
SC928 
SC10U6D3V5KX-4GP 
1 2
SC932 
SC10U6D3V5KX-4GP 
1 2
SR709
10R2F-L-GP
1 2 SC935 
SC22U6D3V5MX-2GP 
1 2
SL3
MPZ2012S601AT-GP
12
SC933 
SC1U6D3V1MX-GP 
1 2
SL6
MPZ2012S601AT-GP
12
SC924 
SC10U6D3V5KX-4GP 
1 2
TP2601
SC917 
SC1U6D3V1MX-GP 
1 2
SC918 
SCD1U6D3V1KX-GP 
1 2
SC927 
SC22U6D3V5MX-2GP 
1 2
SC919 
SC22U6D3V5MX-2GP 
1 2
SR712
10R2F-L-GP
1 2
SL7
MPZ2012S601AT-GP
12
SC925 
SC1U6D3V1MX-GP 
1 2
SC934 
SCD1U6D3V1KX-GP 
1 2
SC922 
SCD1U6D3V1KX-GP 
1 2



5
5
4
4
3
3
2
2
1
1
D D
C C
B B
A A
SAS0_AVDD
PCE_AVDD
SAS0_AVDD
PCE_AVDD
P0V955_C
P0V955_C
SAS0_AVDD
P0V955_C
Title 
Size Document Number R e v 
Date: Sheet 
o f 
Honey badger_LSI Base Board 1B
SAS3008_POWER_2
A3
16 71Tuesday, January 20, 2015
Honey badger_LSI Base Board
http://www.wiwynn.com
8F, 90, Sec.1, Xintai 5th Rd., Xizhi Dist.,
New Taipei City 22102, Taiwan (R.O.C.)
Title 
Size Document Number R e v 
Date: Sheet 
o f 
Honey badger_LSI Base Board 1B
SAS3008_POWER_2
A3
16 71Tuesday, January 20, 2015
Honey badger_LSI Base Board
http://www.wiwynn.com
8F, 90, Sec.1, Xintai 5th Rd., Xizhi Dist.,
New Taipei City 22102, Taiwan (R.O.C.)
Title 
Size Document Number R e v 
Date: Sheet 
o f 
Honey badger_LSI Base Board 1B
SAS3008_POWER_2
A3
16 71Tuesday, January 20, 2015
Honey badger_LSI Base Board
http://www.wiwynn.com
8F, 90, Sec.1, Xintai 5th Rd., Xizhi Dist.,
New Taipei City 22102, Taiwan (R.O.C.)
SR716
D51R3F-2-GP
1 2
8 OF 14 SU2H
SAS3008C0-1-DB-500020657-1-GP
VDDJ12
VDDK13
VDDK21
VDDL14
VDDL16
VDDL18
VDDL20
VDDM11
VDDM13
VDDM15
VDDM17
VDDM19
VDDM21
VDDN12
VDDN14
VDDN16
VDDN18
VDDN20
VDDP13
VDDP15
VDDP17
VDDP19
VDDP21
VDDR12
VDDR14
PPC_VDDG10
PPC_VDDH9
PPC_VDDH11
PPC_VDDJ8
PPC_VDDJ10
PCIE_AVDDAD9
PCIE_AVDDAD11
PCIE_AVDDAD13
PCIE_AVDDAD15
PCIE_AVDDAK6
PCIE_AVDDAK9
PCIE_AVDDAK12
PCIE_AVDDAK15
PCIE_AVDDAK18
VDDA_PCE_REF_CLKAC11
VDD R16
VDD R18
VDD R20
VDD T13
VDD T15
VDD T17
VDD T19
VDD T21
VDD U12
VDD U14
VDD U16
VDD U18
VDD U20
VDD V13
VDD V15
VDD V17
VDD V19
VDD V21
VDD W14
VDD W16
VDD W18
VDD W20
VDD Y17
VDD Y19
VDD Y21
PPC_VDD K9
PPC_VDD K11
PPC_VDD L10
PPC_VDD L12
SAS0_AVDD AB7
SAS0_AVDD AC4
SAS0_AVDD AD7
SAS0_AVDD AF4
SAS0_AVDD AJ3
SAS1_AVDD V7
SAS1_AVDD V9
SAS1_AVDD Y4
SAS1_AVDD Y7
SC951 
SCD1U6D3V1KX-GP 
1 2
SC945 
SC100U6D3V0MX-2GP 
12
SC955 
SCD1U6D3V1KX-GP 
1 2
SC949 
SCD1U6D3V1KX-GP 
1 2
SC953 
SCD1U6D3V1KX-GP 
1 2
SC960 
SCD1U6D3V1KX-GP 
1 2
SC958 
SC1U6D3V1MX-GP 
1 2
SC962 
SCD1U6D3V1KX-GP 
1 2
SC956 
SC100U6D3V0MX-2GP 
12
SC959 
SCD1U6D3V1KX-GP 
1 2
SC961 
SCD1U6D3V1KX-GP 
1 2
SC963 
SCD1U6D3V1KX-GP 
1 2
SC964 
SCD1U6D3V1KX-GP 
1 2
SC948 
SCD1U6D3V1KX-GP 
1 2
SC952 
SCD1U6D3V1KX-GP 
1 2
SR715
D51R3F-2-GP
1 2
SC954 
SCD1U6D3V1KX-GP 
1 2
SC966 
SCD1U6D3V1KX-GP 
1 2
SC950 
SCD1U6D3V1KX-GP 
1 2
SC946 
SC22U6D3V5MX-2GP 
1 2
SC965 
SCD1U6D3V1KX-GP 
1 2
SC947 
SC1U6D3V1MX-GP 
1 2
SL9
28F0181-1SR-10-GP
1 2
SL8
MPZ2012S300AT-GP
1 2 SC957 
SC100U6D3V0MX-2GP 
12



5
5
4
4
3
3
2
2
1
1
D D
C C
B B
A A
0.1uF x 30 
1uF x 6 0.1uF x 6 
10uF x 6 1uF x 6 
0.1uF x 27 
1nF x 8 
1nF x 8 
P1V8_C P1V8_C
P1V8_C
P0V955_CP0V955_C
P0V955_C
P1V8_C
P0V955_C
Title 
Size Document Number R e v 
Date: Sheet 
o f 
Honey badger_LSI Base Board 1B
SAS3008_POWER&GND
A3
17 71Tuesday, January 20, 2015
Honey badger_LSI Base Board
http://www.wiwynn.com
8F, 90, Sec.1, Xintai 5th Rd., Xizhi Dist.,
New Taipei City 22102, Taiwan (R.O.C.)
Title 
Size Document Number R e v 
Date: Sheet 
o f 
Honey badger_LSI Base Board 1B
SAS3008_POWER&GND
A3
17 71Tuesday, January 20, 2015
Honey badger_LSI Base Board
http://www.wiwynn.com
8F, 90, Sec.1, Xintai 5th Rd., Xizhi Dist.,
New Taipei City 22102, Taiwan (R.O.C.)
Title 
Size Document Number R e v 
Date: Sheet 
o f 
Honey badger_LSI Base Board 1B
SAS3008_POWER&GND
A3
17 71Tuesday, January 20, 2015
Honey badger_LSI Base Board
http://www.wiwynn.com
8F, 90, Sec.1, Xintai 5th Rd., Xizhi Dist.,
New Taipei City 22102, Taiwan (R.O.C.)
SC978 
SCD1U16V2KX-3GP 
1 2
SC969 
SC1U10V2KX-4-GP 
1 2
11 OF 14 SU2K
SAS3008C0-1-DB-500020657-1-GP
VSSM27
VSSM28
VSSM29
VSSM30
VSSN1
VSSN2
VSSN4
VSSN7
VSSN8
VSSN9
VSSN10
VSSN11
VSSN13
VSSN15
VSSN17
VSSN19
VSSN21
VSSN22
VSSN23
VSSN24
VSSN25
VSSN26
VSSP3
VSSP7
VSSP8
VSSP9
VSSP10
VSSP11
VSSP12
VSSP14
VSSP16
VSSP18
VSSP20
VSSP22
VSSP23
VSSP24
VSSP25
VSSP27
VSSR1
VSS R2
VSS R3
VSS R4
VSS R8
VSS R9
VSS R10
VSS R11
VSS R13
VSS R15
VSS R17
VSS R19
VSS R21
VSS R22
VSS R23
VSS R24
VSS R25
VSS R26
VSS T3
VSS T5
VSS T7
VSS T8
VSS T10
VSS T11
VSS T12
VSS T14
VSS T16
VSS T18
VSS T20
VSS T22
VSS T23
VSS T24
VSS T25
VSS T27
VSS U2
VSS U3
VSS U4
VSS U5
VSS U6
VSS U7
SC1042 
SCD1U16V2KX-3GP 
1 2
SC1020 
SC10U6D3V5KX-4GP 
1 2
SC1040 
SCD1U16V2KX-3GP 
1 2
SC985 
SCD1U16V2KX-3GP 
1 2
SC1056 
SCD1U16V2KX-3GP 
1 2
SC1047 
SCD1U16V2KX-3GP 
1 2
SC1001 
SCD1U16V2KX-3GP 
1 2
SC1046 
SCD1U16V2KX-3GP 
1 2
SC1034 
SC1KP50V2KX-1GP 
1 2
SC987 
SCD1U16V2KX-3GP 
1 2
SC1048 
SCD1U16V2KX-3GP 
1 2
SC967 
SC1U10V2KX-4-GP 
1 2
SC1060 
SCD1U16V2KX-3GP 
1 2
SC968 
SC1U10V2KX-4-GP 
1 2
SC975 
SCD1U16V2KX-3GP 
1 2
SC994 
SCD1U16V2KX-3GP 
1 2
SC1017 
SC10U6D3V5KX-4GP 
1 2
SC984 
SCD1U16V2KX-3GP 
1 2
SC1008 
SCD1U16V2KX-3GP 
1 2
SC993 
SCD1U16V2KX-3GP 
1 2
SC1028 
SC1U10V2KX-4-GP 
1 2
SC1036 
SC1KP50V2KX-1GP 
1 2
SC1022 
SC10U6D3V5KX-4GP 
1 2
SC1032 
SC1KP50V2KX-1GP 
1 2
SC1043 
SCD1U16V2KX-3GP 
1 2
SC997 
SCD1U16V2KX-3GP 
1 2
SC996 
SCD1U16V2KX-3GP 
1 2
14 OF 14 SU2N
SAS3008C0-1-DB-500020657-1-GP
VSSAE26
VSSAF2
VSSAF3
VSSAF5
VSSAF6
VSSAF9
VSSAF12
VSSAF15
VSSAF18
VSSAF19
VSSAF21
VSSAF23
VSSAF25
VSSAF27
VSSAG3
VSSAG6
VSSAG15
VSSAG20
VSSAG22
VSSAG24
VSSAG26
VSSAH3
VSS AH6
VSS AH7
VSS AH8
VSS AH9
VSS AH10
VSS AH11
VSS AH12
VSS AH13
VSS AH14
VSS AH16
VSS AH17
VSS AH18
VSS AJ2
VSS AJ4
VSS AJ5
VSS AJ6
VSS AJ9
VSS AJ12
VSS AJ15
VSS AJ18
VSS AK2
VSS AK3
SC1057 
SCD1U16V2KX-3GP 
1 2
SC1010 
SC1KP50V2KX-1GP 
1 2
SC995 
SCD1U16V2KX-3GP 
1 2
SC1033 
SC1KP50V2KX-1GP 
1 2
SC1006 
SCD1U16V2KX-3GP 
1 2
SC971 
SC1U10V2KX-4-GP 
1 2
SC1003 
SCD1U16V2KX-3GP 
1 2
SC1044 
SCD1U16V2KX-3GP 
1 2
SC998 
SCD1U16V2KX-3GP 
1 2
SC983 
SCD1U16V2KX-3GP 
1 2
SC1007 
SCD1U16V2KX-3GP 
1 2
SC989 
SCD1U16V2KX-3GP 
1 2
SC1054 
SCD1U16V2KX-3GP 
1 2
SC992 
SCD1U16V2KX-3GP 
1 2
SC986 
SCD1U16V2KX-3GP 
1 2
SC1018 
SC10U6D3V5KX-4GP 
1 2
10 OF 14 SU2J
SAS3008C0-1-DB-500020657-1-GP
VSSH13
VSSH14
VSSH15
VSSH16
VSSH17
VSSH18
VSSH19
VSSH20
VSSH21
VSSH22
VSSH23
VSSH24
VSSH25
VSSH27
VSSJ4
VSSJ7
VSSJ9
VSSJ11
VSSJ13
VSSJ14
VSSJ15
VSSJ16
VSSJ17
VSSJ18
VSSJ19
VSSJ20
VSSJ21
VSSJ22
VSSJ23
VSSJ24
VSSJ25
VSSJ26
VSSK5
VSSK7
VSSK8
VSSK10
VSSK12
VSSK14
VSSK15
VSS K16
VSS K17
VSS K18
VSS K19
VSS K20
VSS K22
VSS K23
VSS K24
VSS K25
VSS K27
VSS L4
VSS L7
VSS L8
VSS L9
VSS L11
VSS L13
VSS L15
VSS L17
VSS L19
VSS L21
VSS L23
VSS L24
VSS L25
VSS L26
VSS L28
VSS M5
VSS M7
VSS M8
VSS M10
VSS M12
VSS M14
VSS M16
VSS M18
VSS M20
VSS M22
VSS M23
VSS M24
VSS M25
VSS M26
SC1021 
SC10U6D3V5KX-4GP 
1 2
SC1014 
SC1KP50V2KX-1GP 
1 2
SC1031 
SC1KP50V2KX-1GP 
1 2
SC1016 
SC1KP50V2KX-1GP 
1 2
SC1019 
SC10U6D3V5KX-4GP 
1 2
SC1063 
SCD1U16V2KX-3GP 
1 2
SC1026 
SC1U10V2KX-4-GP 
1 2
SC1041 
SCD1U16V2KX-3GP 
1 2
SC976 
SCD1U16V2KX-3GP 
1 2
SC1055 
SCD1U16V2KX-3GP 
1 2
SC1058 
SCD1U16V2KX-3GP 
1 2
SC1050 
SCD1U16V2KX-3GP 
1 2
SC1029 
SC1KP50V2KX-1GP 
1 2
SC1023 
SC1U10V2KX-4-GP 
1 2
SC988 
SCD1U16V2KX-3GP 
1 2
SC1051 
SCD1U16V2KX-3GP 
1 2
SC1012 
SC1KP50V2KX-1GP 
1 2
SC1027 
SC1U10V2KX-4-GP 
1 2
SC1039 
SCD1U16V2KX-3GP 
1 2
SC1061 
SCD1U16V2KX-3GP 
1 2
SC1030 
SC1KP50V2KX-1GP 
1 2
SC1000 
SCD1U16V2KX-3GP 
1 2
SC1062 
SCD1U16V2KX-3GP 
1 2
SC991 
SCD1U16V2KX-3GP 
1 2
SC999 
SCD1U16V2KX-3GP 
1 2
SC990 
SCD1U16V2KX-3GP 
1 2
SC1035 
SC1KP50V2KX-1GP 
1 2
SC1024 
SC1U10V2KX-4-GP 
1 2
SC972 
SC1U10V2KX-4-GP 
1 2
13 OF 14 SU2M
SAS3008C0-1-DB-500020657-1-GP
VSSAA19
VSSAA20
VSSAA21
VSSAA22
VSSAA24
VSSAA25
VSSAA26
VSSAB3
VSSAB6
VSSAB8
VSSAB9
VSSAB10
VSSAB11
VSSAB12
VSSAB13
VSSAB14
VSSAB15
VSSAB16
VSSAB17
VSSAB18
VSSAB19
VSSAB20
VSSAB21
VSSAB22
VSSAB23
VSSAB24
VSSAB25
VSSAB27
VSSAC2
VSSAC3
VSSAC5
VSSAC7
VSSAC8
VSSAC9
VSSAC10
VSSAC12
VSSAC13
VSSAC14
VSSAC15
VSS AC16
VSS AC17
VSS AC18
VSS AC19
VSS AC20
VSS AC21
VSS AC22
VSS AC23
VSS AC24
VSS AC25
VSS AC26
VSS AD3
VSS AD6
VSS AD8
VSS AD10
VSS AD12
VSS AD14
VSS AD16
VSS AD17
VSS AD18
VSS AD19
VSS AD20
VSS AD21
VSS AD22
VSS AD23
VSS AD24
VSS AD25
VSS AD27
VSS AE3
VSS AE6
VSS AE7
VSS AE9
VSS AE11
VSS AE13
VSS AE15
VSS AE17
VSS AE18
VSS AE24
VSS AE25
SC1045 
SCD1U16V2KX-3GP 
1 2
SC1005 
SCD1U16V2KX-3GP 
1 2
SC980 
SCD1U16V2KX-3GP 
1 2
SC1004 
SCD1U16V2KX-3GP 
1 2
SC981 
SCD1U16V2KX-3GP 
1 2
SC974 
SCD1U16V2KX-3GP 
1 2
SC1052 
SCD1U16V2KX-3GP 
1 2
SC973 
SCD1U16V2KX-3GP 
1 2
12 OF 14 SU2L
SAS3008C0-1-DB-500020657-1-GP
VSSU8
VSSU9
VSSU11
VSSU13
VSSU15
VSSU17
VSSU19
VSSU21
VSSU22
VSSU23
VSSU24
VSSU25
VSSU26
VSSV3
VSSV6
VSSV8
VSSV10
VSSV12
VSSV14
VSSV16
VSSV18
VSSV20
VSSV22
VSSV23
VSSV24
VSSV25
VSSV27
VSSW3
VSSW6
VSSW7
VSSW8
VSSW9
VSSW10
VSSW11
VSSW12
VSSW13
VSSW15
VSSW17
VSSW19
VSS W21
VSS W22
VSS W23
VSS W24
VSS W25
VSS W26
VSS Y2
VSS Y3
VSS Y5
VSS Y8
VSS Y9
VSS Y10
VSS Y11
VSS Y12
VSS Y13
VSS Y14
VSS Y15
VSS Y16
VSS Y18
VSS Y20
VSS Y22
VSS Y23
VSS Y24
VSS Y25
VSS Y27
VSS AA3
VSS AA6
VSS AA7
VSS AA8
VSS AA9
VSS AA10
VSS AA11
VSS AA12
VSS AA13
VSS AA14
VSS AA15
VSS AA16
VSS AA17
VSS AA18
SC1002 
SCD1U16V2KX-3GP 
1 2
SC1053 
SCD1U16V2KX-3GP 
1 2
SC1013 
SC1KP50V2KX-1GP 
1 2
9 OF 14 SU2I
SAS3008C0-1-DB-500020657-1-GP
VSSA11
VSSA15
VSSB11
VSSB14
VSSB15
VSSC11
VSSC14
VSSC15
VSSD5
VSSD7
VSSD9
VSSD11
VSSD12
VSSD13
VSSD14
VSSD15
VSSD17
VSSD19
VSSD21
VSSD23
VSSD25
VSSD27
VSSE4
VSSE6
VSSE8
VSSE10
VSSE11
VSSE12
VSSE13
VSSE14
VSSE16
VSSE18
VSSE20
VSSE22
VSSE24
VSSE26
VSSF5
VSSF11
VSSF12
VSS F13
VSS F14
VSS F15
VSS F16
VSS F17
VSS F18
VSS F19
VSS F20
VSS F21
VSS F22
VSS F23
VSS F24
VSS F25
VSS F27
VSS G4
VSS G7
VSS G8
VSS G9
VSS G11
VSS G12
VSS G13
VSS G14
VSS G15
VSS G16
VSS G17
VSS G18
VSS G19
VSS G20
VSS G21
VSS G22
VSS G23
VSS G24
VSS G25
VSS G26
VSS H5
VSS H7
VSS H8
VSS H10
VSS H12
SC1049 
SCD1U16V2KX-3GP 
1 2
SC1015 
SC1KP50V2KX-1GP 
1 2
SC977 
SCD1U16V2KX-3GP 
1 2
SC1011 
SC1KP50V2KX-1GP 
1 2
SC1025 
SC1U10V2KX-4-GP 
1 2
SC1059 
SCD1U16V2KX-3GP 
1 2
SC979 
SCD1U16V2KX-3GP 
1 2
SC970 
SC1U10V2KX-4-GP 
1 2
SC1037 
SCD1U16V2KX-3GP 
1 2
SC1038 
SCD1U16V2KX-3GP 
1 2
SC1009 
SC1KP50V2KX-1GP 
1 2
SC982 
SCD1U16V2KX-3GP 
1 2



5
5
4
4
3
3
2
2
1
1
D D
C C
B B
A A
IOC_P3V3_SCL_14 IOC_P3V3_R_SCL_14
EXP_IOC_BMC_R_SDA_14EXP_IOC_BMC_SDA_14 IOC_P3V3_R_SDA_14 IOC_P3V3_SDA_14
EXP_IOC_BMC_R_SCL_14
IOC_SDA_4
IOC_SCL_4 IOC_P3V3_SCL_14
IOC_P3V3_SDA_14
IOC_I2C_VREF
IOC_UART_0_TX_R
IOC_UART_0_RX_R
IOC_UART_R_TX
IOC_UART_R_RX
P3V3
P1V8_C
P1V8_C P3V3_STBY
EXP_IOC_BMC_SCL_14 22,42
EXP_IOC_BMC_SDA_1422,42
IOC_SCL_412
IOC_SDA_412
SYS_RST_N_013
IOC_UART_0_TX13
IOC_UART_0_RX13 IOC_UART_RX 52
IOC_UART_TX 52
PMU_PLTRST_N13,31,33,40,42,44,50,52
Title 
Size Document Number R e v 
Date: Sheet 
o f 
Honey badger_LSI Base Board 1B
SAS3008_I2C&UART LEVEL SHIFT
A3
18 71Tuesday, January 20, 2015
Honey badger_LSI Base Board
http://www.wiwynn.com
8F, 90, Sec.1, Xintai 5th Rd., Xizhi Dist.,
New Taipei City 22102, Taiwan (R.O.C.)
Title 
Size Document Number R e v 
Date: Sheet 
o f 
Honey badger_LSI Base Board 1B
SAS3008_I2C&UART LEVEL SHIFT
A3
18 71Tuesday, January 20, 2015
Honey badger_LSI Base Board
http://www.wiwynn.com
8F, 90, Sec.1, Xintai 5th Rd., Xizhi Dist.,
New Taipei City 22102, Taiwan (R.O.C.)
Title 
Size Document Number R e v 
Date: Sheet 
o f 
Honey badger_LSI Base Board 1B
SAS3008_I2C&UART LEVEL SHIFT
A3
18 71Tuesday, January 20, 2015
Honey badger_LSI Base Board
http://www.wiwynn.com
8F, 90, Sec.1, Xintai 5th Rd., Xizhi Dist.,
New Taipei City 22102, Taiwan (R.O.C.)
SR724 
200KR2F-L-GP 
12
SC1098 
SCD1U16V2KX-3GP 
1 2
SR727
0R2J-2-GP
12
SU63
2N7002DW-7F-GP
1
2
3 4
5
6
SR729
0R2J-2-GP
12
SR928 0R2J-2-GP 12
U184
TXS0102DCUR-1-GP
B2 1
GND 2
VCCA3
A24 A15
OE6
VCCB 7
B1 8
SC1297 
SCD1U16V2KX-3GP 
1 2
SR726 
4K7R2F-GP 
12
SC1287 
SCD1U16V2KX-3GP 
1 2
SR725 
4K7R2F-GP 
12
SR728 0R2J-2-GP1 2
SR926 0R2J-2-GP 12
SR927 0R2J-2-GP 12SR925 0R2J-2-GP 12
SR730 0R2J-2-GP1 2
SC1066 
SCD1U16V2KX-3GP 
1 2
SU62
PCA9306DCTT-GP
GND1
VREF12
SCL13
SDA14 SDA2 5
SCL2 6
VREF2 7
EN 8



5
5
4
4
3
3
2
2
1
1
D D
C C
B B
A A
BLANK 
Title 
Size Document Number R e v 
Date: Sheet 
o f 
Honey badger_LSI Base Board 1B
SAS3008_RESERVE
A3
19 71Tuesday, January 20, 2015
Honey badger_LSI Base Board
http://www.wiwynn.com
8F, 90, Sec.1, Xintai 5th Rd., Xizhi Dist.,
New Taipei City 22102, Taiwan (R.O.C.)
Title 
Size Document Number R e v 
Date: Sheet 
o f 
Honey badger_LSI Base Board 1B
SAS3008_RESERVE
A3
19 71Tuesday, January 20, 2015
Honey badger_LSI Base Board
http://www.wiwynn.com
8F, 90, Sec.1, Xintai 5th Rd., Xizhi Dist.,
New Taipei City 22102, Taiwan (R.O.C.)
Title 
Size Document Number R e v 
Date: Sheet 
o f 
Honey badger_LSI Base Board 1B
SAS3008_RESERVE
A3
19 71Tuesday, January 20, 2015
Honey badger_LSI Base Board
http://www.wiwynn.com
8F, 90, Sec.1, Xintai 5th Rd., Xizhi Dist.,
New Taipei City 22102, Taiwan (R.O.C.)



5
5
4
4
3
3
2
2
1
1
D D
C C
B B
A A
BLANK 
Title 
Size Document Number Rev 
Date: Sheet o f 
Honey badger_LSI Base Board 1B
SAS3008_RESERVE
Custom
20 71Tuesday, January 20, 2015
Honey badger_LSI Base Board
http://www.wiwynn.com
8F, 90, Sec.1, Xintai 5th Rd., Xizhi Dist.,
New Taipei City 22102, Taiwan (R.O.C.)
Title 
Size Document Number Rev 
Date: Sheet o f 
Honey badger_LSI Base Board 1B
SAS3008_RESERVE
Custom
20 71Tuesday, January 20, 2015
Honey badger_LSI Base Board
http://www.wiwynn.com
8F, 90, Sec.1, Xintai 5th Rd., Xizhi Dist.,
New Taipei City 22102, Taiwan (R.O.C.)
Title 
Size Document Number Rev 
Date: Sheet o f 
Honey badger_LSI Base Board 1B
SAS3008_RESERVE
Custom
20 71Tuesday, January 20, 2015
Honey badger_LSI Base Board
http://www.wiwynn.com
8F, 90, Sec.1, Xintai 5th Rd., Xizhi Dist.,
New Taipei City 22102, Taiwan (R.O.C.)



5
5
4
4
3
3
2
2
1
1
D D
C C
B B
A A
SAS_GF_EXP_RX_DP4
SAS_GF_EXP_RX_DN4
SAS_EXP_GF_TX_DP4
SAS_EXP_GF_TX_DN4
SAS_HDD_TX0_P
SAS_HDD_TX0_N
3x24_SAS_TX16_P
3x24_SAS_TX16_N
3x24_SAS_TX17_P
3x24_SAS_TX17_N
SAS_EXP2CONN_RX_N_20
SAS_EXP2CONN_RX_P_20
SAS_EXP2CONN_RX_N_21
SAS_EXP2CONN_RX_P_21
SAS_GF_EXP_RX_DN5
SAS_GF_EXP_RX_DP5
SAS_GF_EXP_RX_DN6
SAS_GF_EXP_RX_DP6
SAS_HDD_CONN_RX7_N
SAS_HDD_CONN_RX7_P
SAS_HDD_CONN_RX8_N
SAS_HDD_CONN_RX8_P
SAS_GF_EXP_RX_DN9
SAS_GF_EXP_RX_DP9
SAS_GF_EXP_RX_DN10
SAS_GF_EXP_RX_DP10
SAS_GF_EXP_RX_DN11
SAS_GF_EXP_RX_DP11
SAS_GF_EXP_RX_DN12
SAS_GF_EXP_RX_DP12
SAS_GF_EXP_RX_DN13
SAS_GF_EXP_RX_DP13
SAS_GF_EXP_RX_DN14
SAS_GF_EXP_RX_DP14
SAS_GF_EXP_RX_DN15
SAS_GF_EXP_RX_DP15
SAS3008_RAID_TX_N0
SAS3008_RAID_TX_P0
SAS3008_RAID_TX_N1
SAS3008_RAID_TX_P1
SAS3008_RAID_TX_N2
SAS3008_RAID_TX_P2
SAS3008_RAID_TX_N3
SAS3008_RAID_TX_P3
SAS_EXP_GF_TX_DN5
SAS_EXP_GF_TX_DP5SAS_HDD_TX1_P
SAS_HDD_TX1_N
SAS_EXP_GF_TX_DN6
SAS_EXP_GF_TX_DP6SAS_HDD_TX2_P
SAS_HDD_TX2_N
SAS_HDD_REDV_TX7_N
SAS_HDD_TX3_P SAS_HDD_REDV_TX7_P
SAS_HDD_TX3_N
SAS_HDD_REDV_TX8_N
SAS_HDD_TX4_P SAS_HDD_REDV_TX8_P
SAS_HDD_TX4_N
SAS_EXP_GF_TX_DN9
SAS_HDD_TX5_P SAS_EXP_GF_TX_DP9
SAS_HDD_TX5_N
SAS_EXP_GF_TX_DN10
SAS_HDD_TX6_P SAS_EXP_GF_TX_DP10
SAS_HDD_TX6_N
SAS_EXP_GF_TX_DN11
SAS_HDD_TX7_P SAS_EXP_GF_TX_DP11
SAS_HDD_TX7_N
SAS_EXP_GF_TX_DN12
SAS_HDD_TX8_P SAS_EXP_GF_TX_DP12
SAS_HDD_TX8_N
SAS_EXP_GF_TX_DN13
SAS_HDD_TX9_P SAS_EXP_GF_TX_DP13
SAS_HDD_TX9_N
SAS_EXP_GF_TX_DN14
SAS_HDD_TX10_P SAS_EXP_GF_TX_DP14
SAS_HDD_TX10_N
SAS_HDD_TX11_P
SAS_EXP_GF_TX_DN15SAS_HDD_TX11_N
SAS_EXP_GF_TX_DP15
SAS_HDD_TX12_P
3008_SAS_RX_N0SAS_HDD_TX12_N
3008_SAS_RX_P0
SAS_HDD_TX13_P
3008_SAS_RX_N1SAS_HDD_TX13_N
3008_SAS_RX_P1
SAS_HDD_TX15_P
3008_SAS_RX_N3SAS_HDD_TX15_N
3008_SAS_RX_P3
SAS_HDD_TX14_P
3008_SAS_RX_N2SAS_HDD_TX14_N
3008_SAS_RX_P2
SAS_EXP2CONN_TX_P_20
SAS_EXP2CONN_TX_N_20
SAS_EXP2CONN_TX_N_21
SAS_EXP2CONN_TX_P_21
SAS_GF_EXP_RX_DN438
SAS_GF_EXP_RX_DP438
SAS_GF_EXP_RX_DP538
SAS_GF_EXP_RX_DN538
SAS_GF_EXP_RX_DN638
SAS_GF_EXP_RX_DP638
SAS_HDD_CONN_RX7_P30
SAS_HDD_CONN_RX7_N30
SAS_HDD_CONN_RX8_N30
SAS_HDD_CONN_RX8_P30
SAS_GF_EXP_RX_DN938
SAS_GF_EXP_RX_DP938
SAS_GF_EXP_RX_DN1038
SAS_GF_EXP_RX_DP1038
SAS_GF_EXP_RX_DP1138
SAS_GF_EXP_RX_DN1138
SAS_GF_EXP_RX_DN1238
SAS_GF_EXP_RX_DP1238
SAS_GF_EXP_RX_DN1338
SAS_GF_EXP_RX_DP1338
SAS_GF_EXP_RX_DN1438
SAS_GF_EXP_RX_DP1438
SAS_GF_EXP_RX_DN1538
SAS_GF_EXP_RX_DP1538
SAS3008_RAID_TX_N011
SAS3008_RAID_TX_P011
SAS3008_RAID_TX_N111
SAS3008_RAID_TX_P111
SAS3008_RAID_TX_N211
SAS3008_RAID_TX_P211
SAS3008_RAID_TX_P311
SAS3008_RAID_TX_N311
SAS_EXP2CONN_RX_N_2030
SAS_EXP2CONN_RX_P_2030
SAS_EXP2CONN_RX_P_2130
SAS_EXP2CONN_RX_N_2130
SAS_EXP_GF_TX_DN4 38
SAS_EXP_GF_TX_DP4 38
SAS_EXP_GF_TX_DP10 38
SAS_EXP_GF_TX_DN10 38
SAS_EXP_GF_TX_DN14 38
SAS_EXP_GF_TX_DP14 38
SAS_EXP_GF_TX_DN5 38
SAS_EXP_GF_TX_DP5 38
SAS_EXP_GF_TX_DN6 38
SAS_EXP_GF_TX_DP6 38
SAS_EXP_GF_TX_DP11 38
SAS_EXP_GF_TX_DN11 38
SAS_HDD_REDV_TX7_N 30
SAS_HDD_REDV_TX7_P 30
SAS_EXP_GF_TX_DN12 38
SAS_EXP_GF_TX_DP12 38
SAS_HDD_REDV_TX8_P 30
SAS_HDD_REDV_TX8_N 30
SAS_EXP_GF_TX_DN13 38
SAS_EXP_GF_TX_DP13 38
SAS_EXP_GF_TX_DP9 38
SAS_EXP_GF_TX_DN9 38
SAS_EXP_GF_TX_DN15 38
SAS_EXP_GF_TX_DP15 38
3008_SAS_RX_N0 11
3008_SAS_RX_P0 11
3008_SAS_RX_N1 11
3008_SAS_RX_P1 11
3008_SAS_RX_N3 11
3008_SAS_RX_P3 11
3008_SAS_RX_N2 11
3008_SAS_RX_P2 11
SAS_EXP2CONN_TX_P_21 30
SAS_EXP2CONN_TX_N_21 30
SAS_EXP2CONN_TX_N_20 30
SAS_EXP2CONN_TX_P_20 30
Title 
Size Document Number R e v 
Date: Sheet 
o f 
Honey badger_LSI Base Board 1B
SAS3X24R SAS PHY A
A3
21 71Tuesday, January 20, 2015
Honey badger_LSI Base Board
http://www.wiwynn.com
8F, 90, Sec.1, Xintai 5th Rd., Xizhi Dist.,
New Taipei City 22102, Taiwan (R.O.C.)
Title 
Size Document Number R e v 
Date: Sheet 
o f 
Honey badger_LSI Base Board 1B
SAS3X24R SAS PHY A
A3
21 71Tuesday, January 20, 2015
Honey badger_LSI Base Board
http://www.wiwynn.com
8F, 90, Sec.1, Xintai 5th Rd., Xizhi Dist.,
New Taipei City 22102, Taiwan (R.O.C.)
Title 
Size Document Number R e v 
Date: Sheet 
o f 
Honey badger_LSI Base Board 1B
SAS3X24R SAS PHY A
A3
21 71Tuesday, January 20, 2015
Honey badger_LSI Base Board
http://www.wiwynn.com
8F, 90, Sec.1, Xintai 5th Rd., Xizhi Dist.,
New Taipei City 22102, Taiwan (R.O.C.)
SC1082 SCD01U10V1KX-GP1 2
SC1261 SCD01U10V1KX-GP1 2
1 OF 11 SU1A
SAS3X24RLC1-DB-500021106-GP
SAS_RXP0U22
SAS_RXN0U21
SAS_RXP1T22
SAS_RXN1T21
SAS_RXP2R22
SAS_RXN2R21
SAS_RXP3P22
SAS_RXN3P21
SAS_RXP4N22
SAS_RXN4N21
SAS_RXP5M22
SAS_RXN5M21
SAS_RXP6L22
SAS_RXN6L21
SAS_RXP7K22
SAS_RXN7K21
SAS_RXP8J22
SAS_RXN8J21
SAS_RXP9H22
SAS_RXN9H21
SAS_RXP10G22
SAS_RXN10G21
SAS_RXP11F22
SAS_RXN11F21
SAS_RXP12AC1
SAS_RXN12AB1
SAS_RXP13AB2
SAS_RXN13AA2
SAS_RXP14AB3
SAS_RXN14AA3
SAS_RXP15AB4
SAS_RXN15AA4
SAS_RXP16AB5
SAS_RXN16AA5
SAS_RXP17AB6
SAS_RXN17AA6
SAS_TXP0 U25
SAS_TXN0 U24
SAS_TXP1 T26
SAS_TXN1 T25
SAS_TXP2 R25
SAS_TXN2 R24
SAS_TXP3 P26
SAS_TXN3 P25
SAS_TXP4 N25
SAS_TXN4 N24
SAS_TXP5 M26
SAS_TXN5 M25
SAS_TXP6 L25
SAS_TXN6 L24
SAS_TXP7 K26
SAS_TXN7 K25
SAS_TXP8 J25
SAS_TXN8 J24
SAS_TXP9 H26
SAS_TXN9 H25
SAS_TXP10 G25
SAS_TXN10 G24
SAS_TXP11 F26
SAS_TXN11 F25
SAS_TXP12 AF2
SAS_TXN12 AE2
SAS_TXP13 AE3
SAS_TXN13 AD3
SAS_TXP14 AF4
SAS_TXN14 AE4
SAS_TXP15 AE5
SAS_TXN15 AD5
SAS_TXP16 AF6
SAS_TXN16 AE6
SAS_TXP17 AE7
SAS_TXN17 AD7
SC1074 SCD01U10V1KX-GP1 2
SC1090 SCD01U10V1KX-GP1 2
SC1265 SCD01U10V1KX-GP1 2
SC1076 SCD01U10V1KX-GP1 2
SC1086 SCD01U10V1KX-GP1 2
SC1067 SCD01U10V1KX-GP1 2
SC1078 SCD01U10V1KX-GP1 2
SC1077 SCD01U10V1KX-GP1 2
SC1263 SCD01U10V1KX-GP1 2
SC1071 SCD01U10V1KX-GP1 2
SC1089 SCD01U10V1KX-GP1 2
SC1091 SCD01U10V1KX-GP1 2
SC1084 SCD01U10V1KX-GP1 2
SC1264 SCD01U10V1KX-GP1 2
SC1092 SCD01U10V1KX-GP1 2
SC1094 SCD01U10V1KX-GP1 2
SC1087 SCD01U10V1KX-GP1 2
SC1068 SCD01U10V1KX-GP1 2
SC1095 SCD01U10V1KX-GP1 2
SC1085 SCD01U10V1KX-GP1 2
SC1096 SCD01U10V1KX-GP1 2
SC1069 SCD01U10V1KX-GP1 2
SC1070 SCD01U10V1KX-GP1 2
SC1073 SCD01U10V1KX-GP1 2
SC1079 SCD01U10V1KX-GP1 2
SC1097 SCD01U10V1KX-GP1 2
SC1088 SCD01U10V1KX-GP1 2
SC1080 SCD01U10V1KX-GP1 2
SC1093 SCD01U10V1KX-GP1 2
SC1083 SCD01U10V1KX-GP1 2
SC1262 SCD01U10V1KX-GP1 2
SC1081 SCD01U10V1KX-GP1 2
SC1075 SCD01U10V1KX-GP1 2
SC1072 SCD01U10V1KX-GP1 2



5
5
4
4
3
3
2
2
1
1
D D
C C
B B
A A
ADD=1010001 (0xA2) 
EXP_EEPROM 
SAS_EXP2CONN_RX_P_22
SAS_EXP2CONN_RX_N_22
SAS_EXP2CONN_RX_P_23
SAS_EXP2CONN_RX_N_23
3x24_SAS_TX19_P
SAS_EXP2CONN_TX_N_23
SAS_EXP2CONN_TX_P_23
3x24_SAS_TX19_N
3x24_SAS_TX18_P
SAS_EXP2CONN_TX_N_22
SAS_EXP2CONN_TX_P_22
3x24_SAS_TX18_N
EXP_SCL_0
EXP_SDA_0
EXP_SIO_CLK_IN
EXP_SIO_CLK_OUT
SIO_D_IN
SIO_D_OUT
SIO_LOAD_IN
SIO_LOAD_OUT
EXP_I2C_SCL_1
EXP_I2C_SDA_1
EXP_I2C_SDA_2
EXP_I2C_SCL_2
EXP_I2C_SDA_3
EXP_I2C_SCL_3
EXP_I2C_SDA_4
EXP_I2C_SCL_4
EXP_RTRIM_A EXP_RTRIM_A_N
EXP_EEPROM_SCL
EXP_EEPROM_WP
EXP_EEPROM_A0
EXP_EEPROM_A1
EXP_EEPROM_A2
EXP_EEPROM_SDA
EXP_I2C_SCL_2
EXP_I2C_SDA_1
EXP_SDA_0
EXP_I2C_SCL_1
EXP_SCL_0
EXP_I2C_SDA_4
EXP_I2C_SCL_4
EXP_I2C_SCL_3
EXP_I2C_SDA_3
EXP_I2C_SDA_2
EXP_I2C_SDA_1
EXP_I2C_SCL_1
EXP_I2C_VREF_0
EXP_I2C_VREF_1
EXP_I2C_SCL_2
EXP_I2C_SDA_2
EXP_I2C_VREF_2
EXP_I2C_SCL_3
EXP_I2C_SDA_3
SAS_GF_EXP_RX_DP0
SAS_GF_EXP_RX_DN0
SAS_GF_EXP_RX_DP1
SAS_GF_EXP_RX_DN1
SAS_GF_EXP_RX_DN2
SAS_GF_EXP_RX_DP2
SAS_GF_EXP_RX_DP3
SAS_GF_EXP_RX_DN3
3x24_SAS_TX20_P
SAS_EXP_GF_TX_DN0
SAS_EXP_GF_TX_DP0
3x24_SAS_TX20_N
3x24_SAS_TX21_N
SAS_EXP_GF_TX_DP1
SAS_EXP_GF_TX_DN1
3x24_SAS_TX21_P
SAS_EXP_GF_TX_DN23x24_SAS_TX22_N
SAS_EXP_GF_TX_DP23x24_SAS_TX22_P
SAS_EXP_GF_TX_DN3
SAS_EXP_GF_TX_DP3
3x24_SAS_TX23_N
3x24_SAS_TX23_P
EXP_I2C_SDA_4
EXP_I2C_SCL_4
EXP_I2C_VREF_3
P1V8_E
P1V8_E
P1V8_E
P1V8_E
P3V3_STBY
P1V8_E
P3V3_STBY
P1V8_E
P3V3_STBY
P1V8_E
P3V3_STBY
P1V8_E
BMC_I2C_F_SCL 42
BMC_I2C_F_SDA 42
EXP_IOC_BMC_SCL_14 18,42
EXP_IOC_BMC_SDA_14 18,42
BMC_I2C_SCL_9 42
BMC_I2C_SDA_9 42
EXP_SCL_0 37
EXP_SDA_0 37
EXP_SDA_037
EXP_SCL_037
BMC_I2C_C_SCL 42,51
BMC_I2C_C_SDA 42,51
SAS_GF_EXP_RX_DP038
SAS_GF_EXP_RX_DN038
SAS_GF_EXP_RX_DN138
SAS_GF_EXP_RX_DP138
SAS_GF_EXP_RX_DN238
SAS_GF_EXP_RX_DP238
SAS_GF_EXP_RX_DP338
SAS_GF_EXP_RX_DN338
SAS_EXP2CONN_RX_N_2330
SAS_EXP2CONN_RX_P_2330
SAS_EXP2CONN_RX_P_2230
SAS_EXP2CONN_RX_N_2230
SAS_EXP_GF_TX_DP0 38
SAS_EXP_GF_TX_DN0 38
SAS_EXP_GF_TX_DP1 38
SAS_EXP_GF_TX_DN1 38
SAS_EXP_GF_TX_DN2 38
SAS_EXP_GF_TX_DP2 38
SAS_EXP_GF_TX_DP3 38
SAS_EXP_GF_TX_DN3 38
SAS_EXP2CONN_TX_P_22 30
SAS_EXP2CONN_TX_N_22 30
SAS_EXP2CONN_TX_P_23 30
SAS_EXP2CONN_TX_N_23 30
Title 
Size Document Number Rev 
Date: Sheet o f 
Honey badger_LSI Base Board 1B
SAS3X24R SAS PHY B&I2C
A2
22 71Tuesday, January 20, 2015
Honey badger_LSI Base Board
http://www.wiwynn.com
8F, 90, Sec.1, Xintai 5th Rd., Xizhi Dist.,
New Taipei City 22102, Taiwan (R.O.C.)
Title 
Size Document Number Rev 
Date: Sheet o f 
Honey badger_LSI Base Board 1B
SAS3X24R SAS PHY B&I2C
A2
22 71Tuesday, January 20, 2015
Honey badger_LSI Base Board
http://www.wiwynn.com
8F, 90, Sec.1, Xintai 5th Rd., Xizhi Dist.,
New Taipei City 22102, Taiwan (R.O.C.)
Title 
Size Document Number Rev 
Date: Sheet o f 
Honey badger_LSI Base Board 1B
SAS3X24R SAS PHY B&I2C
A2
22 71Tuesday, January 20, 2015
Honey badger_LSI Base Board
http://www.wiwynn.com
8F, 90, Sec.1, Xintai 5th Rd., Xizhi Dist.,
New Taipei City 22102, Taiwan (R.O.C.)
TP2651
SR758 
4K7R2F-GP 
1 2
3 OF 11 SU1C
SAS3X24RLC1-DB-500021106-GP
IIC_SCL0E23
IIC_SDA0C25
IIC_SCL1D25
IIC_SDA1D23
IIC_SCL2H18
IIC_SDA2B26
IIC_SCL3B25
IIC_SDA3C23
IIC_SCL4A25
IIC_SDA4G19
SIO_LOAD_OUT G17SIO_LOAD_IN E20
SIO_D_OUT A24SIO_D_IN F19
SIO_CLK_OUT B24SIO_CLK_IN H17
SC1283 
SCD1U16V2KX-3GP 
1 2
SC1105 SCD01U10V1KX-GP1 2
SC1108 
SCD1U16V2KX-3GP 
1 2
SR757 3KR2J-2-GP1 2
TP2641
SR743 
2K2R2F-GP 
12
R608
0R2J-2-GP
1 2
SU78
PCA9306DCTT-GP
GND1
VREF12
SCL13
SDA14 SDA2 5
SCL2 6
VREF2 7
EN 8
SC1294 
SCD1U16V2KX-3GP 
1 2
SR751 
200KR2F-L-GP 
12
SC1284 
SCD1U16V2KX-3GP 
1 2
SC1282 
SCD1U16V2KX-3GP 
1 2
TP2611
SC1106 
SCD1U16V2KX-3GP 
1 2
SC1269 SCD01U10V1KX-GP1 2
SU67
AT24C64D-SSHM-T-GP
A01
A12
A23
GND4
VCC 8
WP 7
SCL 6
SDA 5
SC1267 SCD01U10V1KX-GP1 2
SR760 
4K7R2F-GP 
NOPOP1 2
SR746 
4K7R2F-GP 
12
SR745 
4K7R2F-GP 
12
SR767 
4K7R2F-GP 
1 2
SR763 
4K7R2F-GP 
12
SC1273 SCD01U10V1KX-GP1 2
SR738 
2K2R2F-GP 
12
SR764
0R2J-2-GP
1 2
SC1110 
SCD1U16V2KX-3GP 
1 2
SC1104 SCD01U10V1KX-GP1 2
SC1103 SCD01U10V1KX-GP1 2
SC1271 SCD01U10V1KX-GP1 2
SR747 
4K7R2F-GP 
12
SC1295 
SCD1U16V2KX-3GP 
1 2
SR735 
2K2R2F-GP 
12
SR737 
2K2R2F-GP 
12
SR748 
4K7R2F-GP 
12
R609
0R2J-2-GP
1 2
SR753 
4K7R2F-GP 
12
SR739 
2K2R2F-GP 
12
SC1107 
SCD1U16V2KX-3GP 
1 2
SC1270 SCD01U10V1KX-GP1 2
SU66
PCA9306DCTT-GP
GND1
VREF12
SCL13
SDA14 SDA2 5
SCL2 6
VREF2 7
EN 8
2 OF 11 SU1B
SAS3X24RLC1-DB-500021106-GP
SAS_RXP18AB7
SAS_RXN18AA7
SAS_RXP19AB8
SAS_RXN19AA8
SAS_RXP20AB9
SAS_RXN20AA9
SAS_RXP21AB10
SAS_RXN21AA10
SAS_RXP22AB11
SAS_RXN22AA11
SAS_RXP23AB12
SAS_RXN23AA12
NC#AB13AB13
NC#AA13AA13
NC#AB14AB14
NC#AA14AA14
NC#AB15AB15
NC#AA15AA15
NC#AB16AB16
NC#AA16AA16
NC#AB23AB23
NC#AB22AB22
NC#Y22Y22
NC#Y21Y21
NC#W22W22
NC#W21W21
NC#V22V22
NC#V21V21
NC#AB17AB17
NC#AA17AA17
NC#AB18AB18
NC#AA18AA18
NC#AB19AB19
NC#AA19AA19
NC#AB20AB20
NC#AA20AA20
SAS_TXP18 AF8
SAS_TXN18 AE8
SAS_TXP19 AE9
SAS_TXN19 AD9
SAS_TXP20 AF10
SAS_TXN20 AE10
SAS_TXP21 AE11
SAS_TXN21 AD11
SAS_TXP22 AF12
SAS_TXN22 AE12
SAS_TXP23 AE13
SAS_TXN23 AD13
NC#AF14 AF14
NC#AE14 AE14
NC#AE15 AE15
NC#AD15 AD15
NC#AF16 AF16
NC#AE16 AE16
NC#AE17 AE17
NC#AD17 AD17
NC#AA25 AA25
NC#AA24 AA24
NC#Y26 Y26
NC#Y25 Y25
NC#W25 W25
NC#W24 W24
NC#V26 V26
NC#V25 V25
NC#AF18 AF18
NC#AE18 AE18
NC#AE19 AE19
NC#AD19 AD19
NC#AF20 AF20
NC#AE20 AE20
NC#AE21 AE21
NC#AD21 AD21
RTRIM_AAF23 RTRIM_AN AF24
SR766 
4K7R2F-GP 
1 2
SR740 
2K2R2F-GP 
12
SR744 
2K2R2F-GP 
12
SC1109 
SCD01U50V2KX-1GP 
1 2
SR919 
200KR2F-L-GP 
12
SC1268 SCD01U10V1KX-GP1 2
SU65
PCA9306DCTT-GP
GND1
VREF12
SCL13
SDA14 SDA2 5
SCL2 6
VREF2 7
EN 8
SR754 
200KR2F-L-GP 
12
SR736 
2K2R2F-GP 
12
TP2661
SC1266 SCD01U10V1KX-GP1 2
SR755 
4K7R2F-GP 
12
SR742 
2K2R2F-GP 
12
SR918 
4K7R2F-GP 
12SR752 
4K7R2F-GP 
12
TP2621
SR765 
4K7R2F-GP 
NOPOP1 2
SR761 
200KR2F-L-GP 
12
SC1102 SCD01U10V1KX-GP1 2
SR917 
4K7R2F-GP 
12
SR750 
4K7R2F-GP 
12
TP2631
SU68
PCA9306DCTT-GP
GND1
VREF12
SCL13
SDA14 SDA2 5
SCL2 6
VREF2 7
EN 8
SR762 
4K7R2F-GP 
12
SC1272 SCD01U10V1KX-GP1 2
SR756 
4K7R2F-GP 
12
SR759 
4K7R2F-GP 
NOPOP1 2
SR741 
2K2R2F-GP 
12
SR749 
4K7R2F-GP 
12



5
5
4
4
3
3
2
2
1
1
D D
C C
B B
A A
TRANSCEIVER(EXP GPI) 
B DATA to A BUS 
A DATA to B BUS 
TRANSCEIVER(EXP GPO) 
B DATA to A BUS 
B DATA to A BUS 
For LSI Debug(Eye scope) 
Low Vth=1V 
EXP_GPIO_0
EXP_GPIO_1
EXP_GPIO_2
EXP_GPIO_3
EXP_GPIO_4
EXP_GPIO_5
EXP_GPIO_6
EXP_GPIO_7
EXP_GPIO_8
EXP_GPIO_9
EXP_GPIO_10
EXP_GPIO_11
FCB_HW_REVISION
DPB_HW_REVISION
EXP_SELF_TRAY
PEER_1A_2A_HB
PEER_1B_2B_HB
PEER_TRAY_R
EXP_TRAY_ID
EXP_GPIO_1
EXP_GPIO_8
EXP_GPIO_2
EXP_GPIO_5
EXP_GPIO_6
EXP_GPIO_4
EXP_GPIO_0
EXP_GPIO_7
EXP_GPIO_3
SAS_HDD_LED0
EXP_BLINK_IN
EXP_ADC_IN0
EXP_ADC_IN1
EXP_TEST_MUX24
EXP_TEST_MUX25
EXP_TEST_MUX26
EXP_TEST_MUX27
EXP_TEST_MUX28
EXP_TEST_MUX29
EXP_TEST_MUX30
EXP_TEST_MUX31
EXP_TEST_MUX32
EXP_TEST_MUX33
EXP_TEST_MUX34
EXP_TEST_MUX35
SXP_ACTIVE_0
SXP_ACTIVE_1
SXP_ACTIVE_2
EXP_BLINK_OUT
EXP_TACH_IN0
EXP_TACH_IN1
EXP_TACH_IN2
EXP_TACH_IN3
EXP_PWM_OUT0
EXP_PWM_OUT1
EXP_LED18
EXP_LED19
SAS_HDD_LED20
SAS_HDD_LED21
SAS_HDD_LED22
SAS_HDD_LED23
EXP_FW_DET_BOARD_VER_0
EXP_GPIO_13
SAS_HDD_LED20
SAS_HDD_PRE0
SAS_HDD_PRE1
SAS_HDD_PRE2
SAS_HDD_PRE3
SAS_HDD_PRE4
SAS_HDD_PRE5
SAS_HDD_PRE6
SAS_HDD_PRE7
SAS_HDD_PRE8
SAS_HDD_PRE9
SAS_HDD_PRE10
SAS_HDD_PRE11
SAS_HDD_PRE12
SAS_HDD_PRE13
SAS_HDD_PRE14
SAS_HDD_PRE15
SAS_HDD_LED1
SAS_HDD_LED2
SAS_HDD_LED3
SAS_HDD_LED4
SAS_HDD_LED5
SAS_HDD_LED6
SAS_HDD_LED7
SAS_HDD_LED8
SAS_HDD_LED9
SAS_HDD_LED10
SAS_HDD_LED11
EXP_LED_13
EXP_LED_14
EXP_LED_15
SAS_HDD_LED0
SAS_HDD_LED1
SAS_HDD_LED2
SAS_HDD_LED3
SAS_HDD_LED4
SAS_HDD_LED5
SAS_HDD_LED6
SAS_HDD_LED7
SAS_HDD_LED8
SAS_HDD_LED9
SAS_HDD_LED10
SAS_HDD_LED11
EXP_HDD_PRE_INT_N
EXP_GPIO_13
EXP_GPIO_11
EXP_GPIO_10
EXP_GPIO_9
HDD_PWR_RESET_N
BUS_SW_EN
HDD_LED_RESET_N
EXP_HB
FAN_PWM_PCIe_R
SAS_HDD_LED21
SAS_HDD_LED22
SAS_HDD_LED23
SXP_ACTIVE_0
SXP_ACTIVE_1
EXP_HW_LED_D
EXP_HW_LED_R
EXP_BLINK_OUT
EXP_FW_DET_BOARD_VER_1
EXP_FW_DET_BOARD_VER_2
EXP_FW_DET_BOARD_VER_0
EXP_FW_DET_BOARD_VER_2
EXP_FW_DET_BOARD_VER_1
EXP_LED_12
P1V8_E
P3V3_STBY
P1V8_E
P3V3_STBY
P1V8_E
P1V8_E
P3V3_STBY
P1V8_E
P3V3_STBY
P1V8_E
P3V3_STBY
P1V8_E
P1V8_E
FCB_HW_REVISION 38,44
DPB_HW_REVISION 38,44
EXP_SELF_TRAY 38
PEER_1A_2A_HB 38,44
PEER_1B_2B_HB 38,44
PEER_TRAY_R 38,44
EXP_TRAY_ID 38,44
SAS_HDD_PRE0 37,38
SAS_HDD_PRE1 37,38
SAS_HDD_PRE2 37,38
SAS_HDD_PRE3 37,38
SAS_HDD_PRE4 37,38
SAS_HDD_PRE5 37,38
SAS_HDD_PRE6 37,38
SAS_HDD_PRE7 37,38
SAS_HDD_PRE8 37,38
SAS_HDD_PRE9 37,38
SAS_HDD_PRE10 37,38
SAS_HDD_PRE11 37,38
SAS_HDD_PRE12 37,38
SAS_HDD_PRE13 37,38
SAS_HDD_PRE14 37,38
SAS_HDD_PRE15 37,38
EXP_HDD_PRE_INT_N 37
HDD_PWR_RESET_N 37
HDD_LED_RESET_N 37
BUS_SW_EN 37
EXP_HB 32
FAN_PWM_PCIe 38,44
SAS_Activity_LED1630
SAS_Status_LED1730
SYS_RST_N_025
Title 
Size Document Number R e v 
Date: Sheet 
o f 
Honey badger_LSI Base Board 1B
SAS3X24R LED&GPIO
A3
23 71Tuesday, January 20, 2015
Honey badger_LSI Base Board
http://www.wiwynn.com
8F, 90, Sec.1, Xintai 5th Rd., Xizhi Dist.,
New Taipei City 22102, Taiwan (R.O.C.)
Title 
Size Document Number R e v 
Date: Sheet 
o f 
Honey badger_LSI Base Board 1B
SAS3X24R LED&GPIO
A3
23 71Tuesday, January 20, 2015
Honey badger_LSI Base Board
http://www.wiwynn.com
8F, 90, Sec.1, Xintai 5th Rd., Xizhi Dist.,
New Taipei City 22102, Taiwan (R.O.C.)
Title 
Size Document Number R e v 
Date: Sheet 
o f 
Honey badger_LSI Base Board 1B
SAS3X24R LED&GPIO
A3
23 71Tuesday, January 20, 2015
Honey badger_LSI Base Board
http://www.wiwynn.com
8F, 90, Sec.1, Xintai 5th Rd., Xizhi Dist.,
New Taipei City 22102, Taiwan (R.O.C.)
STP671
SC1114
SCD1U16V2KX-3GP
1 2
SC1115
SCD1U16V2KX-3GP
1 2 SR823
4K75R2F-1-GP
NOPOP
1 2
SR821
4K75R2F-1-GP
1 2
SC1121
SCD1U16V2KX-3GP
1 2
SC308
SCD1U16V2KX-3GP
1 2
SC1116
SCD1U16V2KX-3GP
1 2
SR773 4K75R2F-1-GP12
SR768 4K75R2F-1-GP12
SR822
4K75R2F-1-GP
NOPOP
1 2
SU69
SNLVC8T245DGVR-GP
A13
A24
A35
A46
A57
A68
A79
A810
B1 21
B2 20
B3 19
B4 18
B5 17
B6 16
B7 15
B8 14
VCCA1
DIR2
VCCB24
VCCB23
GND 11
GND 12
GND 13
OE# 22
STP651
SR920 0R2J-2-GPNOPOP1 2
STP731
STP811
STP681
STP571
SR771 4K75R2F-1-GP12
SLED27
LED-YG-51-GP
A K
STP821
4 OF 11 SU1D
SAS3X24RLC1-DB-500021106-GP
GPIO0A21
GPIO1C19
GPIO2B20
GPIO3E17
GPIO4H15
GPIO5B19
GPIO6A20
GPIO7B18
GPIO8D17
GPIO9G15
GPIO10E16
GPIO11A19
GPIO12A18
GPIO13C17
GPIO14F15
GPIO15A17
LED0E2
LED1E1
LED2F2
LED3G6
LED4F1
LED5G3
LED6G2
LED7H5
LED8H6
LED9H2
LED10G1
LED11J2
LED12K2
LED13K4
LED14L5
LED15K1
LED16P7
LED17L2
ADC_IN0 J3
ADC_IN1 J5
PWM_OUT0 D15
PWM_OUT1 A16
TACH_IN0 B17
TACH_IN1 B16
TACH_IN2 E15
TACH_IN3 H14
BLINK_IN E3
BLINK_OUT D1
SXP_ACTIVE0 G5
SXP_ACTIVE1 H8
SXP_ACTIVE2 G4
LED18 L4
LED19 M5
LED20 M4
LED21 P5
LED22 N5
LED23 L1
TEST_MUX24 N4
TEST_MUX25 M2
TEST_MUX26 R5
TEST_MUX27 N2
TEST_MUX28 M1
TEST_MUX29 N1
TEST_MUX30 P4
TEST_MUX31 R7
TEST_MUX32 P1
TEST_MUX33 P2
TEST_MUX34 R1
TEST_MUX35 R2
STP711
SU70
SNLVC8T245DGVR-GP
A13
A24
A35
A46
A57
A68
A79
A810
B1 21
B2 20
B3 19
B4 18
B5 17
B6 16
B7 15
B8 14
VCCA1
DIR2
VCCB24
VCCB23
GND 11
GND 12
GND 13
OE# 22
STP1441
SR770 4K75R2F-1-GP12
SU71
SNLVC8T245DGVR-GP
A13
A24
A35
A46
A57
A68
A79
A810
B1 21
B2 20
B3 19
B4 18
B5 17
B6 16
B7 15
B8 14
VCCA1
DIR2
VCCB24
VCCB23
GND 11
GND 12
GND 13
OE# 22
STP751
SC1112
SCD1U16V2KX-3GP
1 2
STP801
STP691
SC1117
SCD1U16V2KX-3GP
1 2
SC307
SCD1U16V2KX-3GP
1 2
SC1118
SCD1U16V2KX-3GP
1 2
SC1113
SCD1U16V2KX-3GP
1 2
STP621
STP157 1
STP831
STP871
STP156 1
STP631
SR824
4K75R2F-1-GP
NOPOP
1 2
SR826
4K75R2F-1-GP
1 2
STP561
SR772 4K75R2F-1-GP12
SR957
0R2J-2-GP
1 2
STP1451
SR825
4K75R2F-1-GP
1 2
SC1119
SCD1U16V2KX-3GP
1 2
STP154 1
SU72
SNLVC8T245DGVR-GP
A13
A24
A35
A46
A57
A68
A79
A810
B1 21
B2 20
B3 19
B4 18
B5 17
B6 16
B7 15
B8 14
VCCA1
DIR2
VCCB24
VCCB23
GND 11
GND 12
GND 13
OE# 22
SR731 
150R2F-1-GP 
1 2
STP661
STP701
SR704
10KR2F-2-GP
1 2
STP861
SC1120
SCD1U16V2KX-3GP
1 2
STP641
SC1111
SCD1U16V2KX-3GP
1 2
SQ5
AO3400A-GP
G
D S
SR769 4K75R2F-1-GP12



5
5
4
4
3
3
2
2
1
1
D D
C C
B B
A A
EXP_XM_ADDR_25
EXP_XM_ADDR_19
EXP_XM_ADDR_16
EXP_XM_ADDR_15
EXP_XM_ADDR_24
EXP_XM_ADDR_22
EXP_XM_ADDR_21
EXP_XM_ADDR_20
EXP_XM_ADDR_14
EXP_XM_ADDR_12
EXP_XM_ADDR_13
EXP_XM_ADDR_11
EXP_XM_ADDR_10
EXP_XM_ADDR_8
EXP_XM_ADDR_9
EXP_XM_ADDR_7
EXP_XM_ADDR_6
EXP_XM_ADDR_4
EXP_XM_ADDR_5
EXP_XM_ADDR_3
EXP_XM_ADDR_1
EXP_XM_ADDR_2
EXP_XM_ADDR_0 XM_DATA0
XM_DATA1
XM_DATA2
XM_DATA3
XM_DATA4
XM_DATA5
XM_DATA6
XM_DATA7
XM_DATA8
XM_DATA9
XM_DATA10
XM_DATA11
XM_DATA12
XM_DATA13
XM_DATA14
XM_DATA15
EXP_XM_ADDR_18
EXP_XM_BUSY_N
EXP_XM_OE_N
EXP_XM_NOR_CS_N
EXP_XM_ADDR_17
EXP_XM_ADDR_23
EXP_XM_CS_N_0
EXP_XM_WE_N
EXP_XM_BUSY_N
XM_DATA15
XM_DATA14
XM_DATA13
XM_DATA12
XM_DATA11
XM_DATA10
XM_DATA9
XM_DATA8
XM_DATA7
XM_DATA6
XM_DATA5
XM_DATA4
XM_DATA3
XM_DATA2
XM_DATA1
XM_DATA0
EXP_XM_ADDR_1
EXP_XM_ADDR_2
EXP_XM_ADDR_3
EXP_XM_ADDR_4
EXP_XM_ADDR_5
EXP_XM_ADDR_6
EXP_XM_ADDR_7
EXP_XM_ADDR_8
EXP_XM_ADDR_9
EXP_XM_ADDR_10
EXP_XM_ADDR_11
EXP_XM_ADDR_12
EXP_XM_ADDR_13
EXP_XM_ADDR_14
EXP_XM_ADDR_15
EXP_XM_ADDR_16
EXP_XM_ADDR_17
EXP_XM_ADDR_18
EXP_XM_ADDR_19
EXP_XM_ADDR_20
EXP_XM_ADDR_21
EXP_XM_ADDR_22
EXP_XM_ADDR_23
RESET_N
EXP_WP_N
EXP_XM_OE_N
EXP_XM_WE_N
EXP_XM_NOR_CS_N
P1V8_E
P1V8_E
P3V3_STBYP1V8_E
P1V8_E
P1V8_E
RESET_N 25
Title 
Size Document Number R e v 
Date: Sheet 
o f 
Honey badger_LSI Base Board 1B
SAS3X24R MEMORIES
A3
24 71Tuesday, January 20, 2015
Honey badger_LSI Base Board
http://www.wiwynn.com
8F, 90, Sec.1, Xintai 5th Rd., Xizhi Dist.,
New Taipei City 22102, Taiwan (R.O.C.)
Title 
Size Document Number R e v 
Date: Sheet 
o f 
Honey badger_LSI Base Board 1B
SAS3X24R MEMORIES
A3
24 71Tuesday, January 20, 2015
Honey badger_LSI Base Board
http://www.wiwynn.com
8F, 90, Sec.1, Xintai 5th Rd., Xizhi Dist.,
New Taipei City 22102, Taiwan (R.O.C.)
Title 
Size Document Number R e v 
Date: Sheet 
o f 
Honey badger_LSI Base Board 1B
SAS3X24R MEMORIES
A3
24 71Tuesday, January 20, 2015
Honey badger_LSI Base Board
http://www.wiwynn.com
8F, 90, Sec.1, Xintai 5th Rd., Xizhi Dist.,
New Taipei City 22102, Taiwan (R.O.C.)
SR778 
4K7R2F-GP 
1 2
SR782 
4K7R2F-GP 
1 2
SR786
4K75R2F-1-GP
1 2
SR779 
4K7R2F-GP 
1 2
SR780 
4K7R2F-GP 
1 2
SC1100 
SCD1U16V2KX-3GP 
1 2
SR774
34KR2F-GP
1 2
SR784
10KR2F-2-GP
1 2
SR775
4K75R2F-1-GP
1 2
SR781 
4K7R2F-GP 
1 2
STP164 1
5 OF 11 SU1E
SAS3X24RLC1-DB-500021106-GP
XM_ADDR0C15
XM_ADDR1B15
XM_ADDR2F13
XM_ADDR3A11
XM_ADDR4C11
XM_ADDR5D11
XM_ADDR6G12
XM_ADDR7A10
XM_ADDR8E11
XM_ADDR9B10
XM_ADDR10G14
XM_ADDR11E14
XM_ADDR12A15
XM_ADDR13B14
XM_ADDR14A14
XM_ADDR15F14
XM_ADDR16D13
XM_ADDR17E13
XM_ADDR18C13
XM_ADDR19B13
XM_ADDR20A12
XM_ADDR21A13
XM_ADDR22B12
XM_ADDR23E12
XM_ADDR24H12
XM_ADDR25B11
XM_DATA0 F12
XM_DATA1 A8
XM_DATA2 D9
XM_DATA3 B7
XM_DATA4 F10
XM_DATA5 B6
XM_DATA6 A6
XM_DATA7 C7
XM_DATA8 A5
XM_DATA9 G10
XM_DATA10 B9
XM_DATA11 C9
XM_DATA12 E10
XM_DATA13 F11
XM_DATA14 A7
XM_DATA15 B8
XM_RE# A4
XM_WE# C4
XM_WBE0# E7
XM_WBE1# A3
XM_BUSY# A9
XM_NOR_CS# F9
XM_GP_CS0# B5
XM_GP_CS1# D7
XM_GP_CS2# E8
XM_GP_CS3# C5
SR785
10KR2F-2-GP
1 2
SC1101 
SCD1U16V2KX-3GP 
1 2
SU73
S29GL128S10TFIV20-GP
NC#55 55
VSS 52
VCC43
VSS 33
VIO29
A031
A126
A225
A324
A423
A522
A621
A720
A810
A99
A108
A117
A126
A135
A144
A153
A1654
A1719
A1818
A1911
A2012
A2115
A222
NC#1 1
NC#56 56
DQ0 35
DQ1 37
DQ2 39
DQ3 41
DQ4 44
DQ5 46
DQ6 48
DQ7 50
DQ8 36
DQ9 38
DQ10 40
DQ11 42
DQ12 45
DQ13 47
DQ14 49
DQ15 51
DNU 28
RFU#27 27
RFU#30 30
RFU#53 53
OE#34
CE#32
WE#13
WP#16
RESET# 14
RY/BY# 17
SR776 
4K7R2F-GP 
1 2
STP163 1STP162 1
SR777 
4K7R2F-GP 
1 2



5
5
4
4
3
3
2
2
1
1
D D
C C
B B
A A
ICE CONN 
EXP_CPU_MODE_0
EXP_CPU_MODE_1
EXP_CLK_SEL0 EXP_CLK_SEL1
EXP_CLK_SEL1
EXP_CLK_SEL0
EXP_REF_CLK_N
EXP_REF_CLK_P
PHY_CLK
EXP_RESET_N
RESET_N
TEST_MUX_36
TEST_MUX_37
TEST_MUX_38
TEST_MUX_39
TEST_MUX_40
TEST_MUX_41
TEST_MUX_42
TEST_MUX_43
TEST_MUX_44
TEST_MUX_45
TEST_MUX_46
TEST_MUX_47
TEST_MUX_46
TEST_MUX_47
TMUX_EN
TMUX_EN
TESTIBIAS
LSI_PROCMON
LSI_SCAN_ENABLE
LSI_T_N
LSI_EFUSE
EXP_IDDT
LSI_TRST_N
JTAG_EXP_TCK
JTAG_EXP_TMS
LSI_TRST_N
LSI_EFUSE
EXP_IDDT
LSI_SCAN_ENABLE
ICE_TCK
ICE_TDI
ICE_TDO
ICE_TMS
ICE_TRST_N
ICE_TDO
3D3V_ICE
ICE_TRST_N
ICE_TMS
ICE_RESET_N
ICE_TCK
ICE_TDI
SDB_R_TX
SMART_TX
SDB_R_RX
SMART_RX
UART_CTS
UART_RTS
EXP_RESET_N
SDB_TX
TMUX_EN
LSI_SCAN_ENABLE
SAS_SMART_RX
SAS_SMART_TX
UART_CTS
LSI_T_N
SDB_RX
ICE_RESET_N
RESET_AND_N
P3V3_STBY_G4
EXP_RST
P3V3_STBY_R4
EXP_RESET_MR_N
EXP_RESET_MR_N
JTAG_EXP_TDI
EXP_REF_CLK_N
P3V3_STBY_G5
EXP_RST_R
P3V3_STBY_R5
BMC_EXP_RESET_N
BMC_EXP_RESET_N
JTAG_EXP_TDO_R
P3V3_STBY_G7
RST_BTN_R
P3V3_STBY_R7
RST_BTN_N
P3V3_STBY_G8
DP_EXP_RST_R
P3V3_STBY_R8
DP_EXP_RST
RST_BTN_N
DP_EXP_RST
EXP_RST_1
JTAG_EXP_TCK
JTAG_EXP_TDI
JTAG_EXP_TDO_R
JTAG_EXP_TMS
LSI_TRST_N
EXP_REF_CLK_P
EXP_REF_CLK_N_R
EXP_RST_2
SOFT_RESET_N
P1V8_E
P1V8_E
P1V8_EP1V8_E
P1V8_STBY
P1V8_E
P1V8_E
P3V3_STBY
P3V3_STBY
P1V8_E
P3V3_STBY
P1V8_E
P1V8_E
P3V3_STBY
P3V3_STBY
P1V8_E
P3V3_STBY
P1V8_E
P1V8_E
P1V8_E
P1V8_E
P1V8_STBY
SDB_TX 29
SDB_RX 29
SAS_SMART_TX 29
SAS_SMART_RX 29
P0V9_E_PG33,43,62,64
BMC_RST_EXPANDER43
CPU_EXP_RESET_N53
DP_BMC_EXP_RST_N44
RESET_N 24
JTAG_BMC_L_TDO 36
JTAG_EXP_IOC_TCK 13,36
JTAG_EXP_IOC_TMS 13,36
JTAG_EXP_IOC_RST 13,36
JTAG_EXP_TDO 36
Title 
Size Document Number Rev 
Date: Sheet o f 
Honey badger_LSI Base Board 1B
SAS3X24R MISC
A2
25 71Tuesday, January 20, 2015
Honey badger_LSI Base Board
http://www.wiwynn.com
8F, 90, Sec.1, Xintai 5th Rd., Xizhi Dist.,
New Taipei City 22102, Taiwan (R.O.C.)
Title 
Size Document Number Rev 
Date: Sheet o f 
Honey badger_LSI Base Board 1B
SAS3X24R MISC
A2
25 71Tuesday, January 20, 2015
Honey badger_LSI Base Board
http://www.wiwynn.com
8F, 90, Sec.1, Xintai 5th Rd., Xizhi Dist.,
New Taipei City 22102, Taiwan (R.O.C.)
Title 
Size Document Number Rev 
Date: Sheet o f 
Honey badger_LSI Base Board 1B
SAS3X24R MISC
A2
25 71Tuesday, January 20, 2015
Honey badger_LSI Base Board
http://www.wiwynn.com
8F, 90, Sec.1, Xintai 5th Rd., Xizhi Dist.,
New Taipei City 22102, Taiwan (R.O.C.)
Q15
2N7002A-7-GP
G
SD
STP1101
SR1275
10KR2F-2-GP
1 2
SR860
1KR2J-1-GP
12
SR7930R2J-2-GP 1 2
SR796
4K75R2F-1-GP
1 2
STP1031
STP1051
SR856
1KR2J-1-GP
12
STP981
SX2
XTAL-25MHZ-105-GP
4 1
23
SR809 
4K75R2F-1-GP 
1 2
STP881
SR914
0R2J-2-GP
12
SR923 0R2J-2-GP1 2
STP961
STP1461
SR820 1KR2F-3-GP1 2
STP891
SR1273
0R2J-2-GP
12
SCN3
MLX-CONN20A-S3-GP
NOPOP
1
3
5
7
9
11
13
15
17
19
2
4
6
8
10
12
14
16
18
20
SR810 
4K75R2F-1-GP 
1 2
SR808 4K75R2F-1-GP12
SR800 4K75R2F-1-GP12
SR791
4K7R2F-GP
1 2
SR7900R2J-2-GP 1 2
SC1122
SCD1U16V2KX-3GP
1 2
SR801 4K75R2F-1-GPNOPOP 12
SR812 
4K75R2F-1-GP 
1 2
6 OF 11 SU1F
SAS3X24RLC1-DB-500021106-GP
REF_CLKPW2
PHY_CLKD19
POR_RESET#D5
RESET#A2
CPU_MODE0F8
NC#R9R9
CPU_MODE1E5
FSEL0H10
FSEL1E6
REF_CLKNW1
SOFT_RESET#C3
NC#J9J9
SDB_RX E18
SDB_TX A22
UART_CTS D21
UART_RTS A23
UART_RX B23
UART_TX B22
ICE_TCK F17
ICE_TDI F18
ICE_TDO E19
ICE_TMS B21
ICE_TRST# C21
LSI_TCK F5
LSI_TDI C2
LSI_TDO E4
LSI_TMS C1
LSI_TRST# D2
LSI_IDDT B2
LSI_SCAN_ENABLE G8
LSI_T# F7
EFUSE_CONNECT F16
LSI_PROCMON B1
TESTIBIAS J4
TMUX_EN F6
TEST_MUX36 T5
TEST_MUX37 T1
TEST_MUX38 R4
TEST_MUX39 T2
TEST_MUX40 T4
TEST_MUX41 T7
TEST_MUX42 U2
TEST_MUX43 U1
TEST_MUX44 V4
TEST_MUX45 U4
TEST_MUX46 U5
TEST_MUX47 V5
SC1123
SCD1U16V2KX-3GP
1 2
STP1471
SR1276
1KR2J-1-GP
12
STP1141
SU75
TPS3808G18DRVT-GP-U
VDD1
SENSE2
CT3
MR# 4GND 5RESET# 6GND 7
STP1491
SR799
4K75R2F-1-GP
NOPOP1 2
SR859 0R2J-2-GP1 2
SR819 4K75R2F-1-GP12
SR818 4K75R2F-1-GP12
SR915
10KR2F-2-GP
1 2
STP971
SR1279
4K7R2F-GP
1 2
SR789 4K75R2F-1-GP12
SR803 4K75R2F-1-GP12
SR795
4K7R2F-GP
1 2
SR858
0R2J-2-GP
12
STP1071
SQ12
2N7002A-7-GP
G
SD
SR857
4K7R2F-GP
1 2
SR798
4K75R2F-1-GP
NOPOP1 2
STP991
STP1001
SR806 4K75R2F-1-GP12
SR861 0R2J-2-GP1 2
SR1280
10KR2F-2-GP
1 2
SR817 4K75R2F-1-GP12
SR7880R2J-2-GP 1 2
STP1011
STP1081
SR1277
0R2J-2-GP
12
SU80
SN74LVC1G08DCKR-GP
B2
A1
GND3 Y 4
VCC 5
SR816 4K75R2F-1-GP12
SR597
0R2J-2-GP
1 2
SR867 0R2J-2-GP1 2
SR1274
4K7R2F-GP
1 2
SR802 4K75R2F-1-GPNOPOP 12
SR1278
4K7R2F-GP
1 2
SU79
SN74LVC1G08DCKR-GP
B2
A1
GND3 Y 4
VCC 5
SC1124
SC12P50V2JN-3GP
1 2
SR794
10KR2F-2-GP12
SQ13
2N7002A-7-GP
G
SD
STP1041
STP1131
SQ17
2N7002A-7-GP
G
SD
SQ14
2N7002A-7-GP
G
SD
SR1272
1KR2J-1-GP
12
SR787 4K75R2F-1-GP12
SR805 4K75R2F-1-GP12
SR814 1KR2F-3-GPNOPOP1 2
SR854
4K7R2F-GP
1 2
SQ15
2N7002A-7-GP
G
SD
SR815 1KR2F-3-GPNOPOP1 2
SQ16
2N7002A-7-GP
G
SD
SR855
10KR2F-2-GP
1 2
STP1481
SR807
0R3J-0-U-GP
1 2
Q14
2N7002A-7-GP
G
SD
SR916
4K7R2F-GP
1 2
STP1111
SR811 
4K75R2F-1-GP 
1 2
STP1061
SR804 4K75R2F-1-GP12
STP1501
STP1121
SR862 0R2J-2-GP1 2
STP1091
STP1021
SC1125
SC12P50V2JN-3GP
1 2
STP90 1
SU76
SOLVC2G07DBVR-GP
1A1
GND2
2A3 2Y 4VCC 51Y 6
SR813 
4K75R2F-1-GP 
1 2
SR797
4K75R2F-1-GP1 2
U39
SN74LVC1G08DCKR-GP
B2
A1
GND3 Y 4
VCC 5
SR7920R2J-2-GP 1 2



5
5
4
4
3
3
2
2
1
1
D D
C C
B B
A A
XTAL_VDDA18SYSPLL_VDDA18 PLLDDR_VDDA18
GB_VDDH2
P1V8_E
GB_VDDH2
GB_VDDH2
P1V8_E
PLLDDR_VDDA18
XTAL_VDDA18
SYSPLL_VDDA18
P1V8_EP1V8_E P1V8_E
P1V5_E
Title 
Size Document Number R e v 
Date: Sheet 
o f 
Honey badger_LSI Base Board 1B
SAS3X24R POWER_1
A3
26 71Tuesday, January 20, 2015
Honey badger_LSI Base Board
http://www.wiwynn.com
8F, 90, Sec.1, Xintai 5th Rd., Xizhi Dist.,
New Taipei City 22102, Taiwan (R.O.C.)
Title 
Size Document Number R e v 
Date: Sheet 
o f 
Honey badger_LSI Base Board 1B
SAS3X24R POWER_1
A3
26 71Tuesday, January 20, 2015
Honey badger_LSI Base Board
http://www.wiwynn.com
8F, 90, Sec.1, Xintai 5th Rd., Xizhi Dist.,
New Taipei City 22102, Taiwan (R.O.C.)
Title 
Size Document Number R e v 
Date: Sheet 
o f 
Honey badger_LSI Base Board 1B
SAS3X24R POWER_1
A3
26 71Tuesday, January 20, 2015
Honey badger_LSI Base Board
http://www.wiwynn.com
8F, 90, Sec.1, Xintai 5th Rd., Xizhi Dist.,
New Taipei City 22102, Taiwan (R.O.C.)
SC1156 
SC1U6D3V1MX-GP 
1 2
SC1154 
SC22U6D3V5MX-2GP 
1 2
SC1149 
SCD1U6D3V1KX-GP 
1 2
SC1141 
SCD1U6D3V1KX-GP 
1 2
SC1139 
SCD1U6D3V1KX-GP 
1 2
SC1146 
SC22U6D3V5MX-2GP 
1 2
SR827
D51R3F-2-GP
1 2
SR829
10R2F-L-GP
1 2
SC1153 
SCD1U6D3V1KX-GP 
1 2
SC1157 
SCD1U6D3V1KX-GP 
1 2
SC1132 
SC100U6D3V0MX-2GP 
12
SC1133 
SC1U6D3V1MX-GP 
1 2
SC1131 
SC100U6D3V0MX-2GP 
12
SL12
MPZ2012S601AT-GP
12
SC1152 
SC1U6D3V1MX-GP 
1 2
SL11
MPZ2012S300AT-GP
1 2
SR828
10R2F-L-GP
1 2
SC1151 
SC10U6D3V5KX-4GP 
1 2
SC1145 
SCD1U6D3V1KX-GP 
1 2
SL13
MPZ2012S601AT-GP
12
SC1134 
SCD1U6D3V1KX-GP 
1 2
SC1150 
SC22U6D3V5MX-2GP 
1 2
SC1140 
SCD1U6D3V1KX-GP 
1 2
SC1155 
SC10U6D3V5KX-4GP 
1 2
SC1147 
SC10U6D3V5KX-4GP 
1 2
SC1137 
SCD1U6D3V1KX-GP 
1 2
SR830
10R2F-L-GP
1 2
SC1148 
SC1U6D3V1MX-GP 
1 2
7 OF 11 SU1G
SAS3X24RLC1-DB-500021106-GP
VDDIO18_GPIO_1D8
VDDIO18_GPIO_1D26
VDDIO18_GPIO_1E9
VDDIO18_GPIO_1F4
VDDIO18_GPIO_1B4
VDDIO18_GPIO_1D4
VDDIO18_GPIO_1D6
VDDIO18_GPIO_1D14
VDDIO18_GPIO_1D16
VDDIO18_GPIO_1D18
VDDIO18_GPIO_1D20
VDDIO18_GPIO_1D22
VDDIO18_GPIO_1D24
VDDIO18_GPIO_1D10
VDDIO18_GPIO_1D12
VDDIO18_GPIO_1H4
GB_VDDH2_1K19
GB_VDDH2_1L19
GB_VDDH2_1M19
GB_VDDH2_1N19
GB_VDDH2_1P19
GB_VDDH2_2V8
ADCTEMP_VDDA18J1
PLLDDR_VDDA18N7
VDDIO18_GPIO_1 H11
VDDIO18_GPIO_1 H13
VDDIO18_GPIO_1 H9
VDDIO18_GPIO_1 T6
VDDIO18_GPIO_1 U3
VDDIO18_GPIO_1 H16
VDDIO18_GPIO_1 H7
VDDIO18_GPIO_1 K6
VDDIO18_GPIO_1 L3
VDDIO18_GPIO_1 M6
VDDIO18_GPIO_1 N3
VDDIO18_GPIO_1 P6
VDDIO18_GPIO_1 R3
VDDIO18_GPIO_1 J6
VDDIO18_GPIO_1 J15
GB_VDDH2_2 V11
GB_VDDH2_2 V12
GB_VDDH2_2 V13
GB_VDDH2_2 V14
GB_VDDH2_2 V15
GB_VDDH2_2 V10
SYSPLL_VDDA18 M7
XTAL_VDDA18 W3
GB_VDDH2_2 V9
SC1136 
SCD1U6D3V1KX-GP 
1 2
SC1135 
SCD1U6D3V1KX-GP 
1 2
SC1143 
SCD1U6D3V1KX-GP 
1 2
SC1138 
SCD1U6D3V1KX-GP 
1 2
SC1144 
SCD1U6D3V1KX-GP 
1 2
SC1142 
SCD1U6D3V1KX-GP 
1 2
SL14
MPZ2012S601AT-GP
12



5
5
4
4
3
3
2
2
1
1
D D
C C
B B
A A
GB_VDDA
GB_VDDA
GB_VDDA
GB_VDDA
GB_VDDA
GB_VDDA
XTAL_VDDA09
SYSPLL_VDDA09
GB_VDDA GB_VDDA
XTAL_VDDA09
P0V9_E
SYSPLL_VDDA09
P0V9_E
P0V9_E
P0V9_E
P0V9_E
P0V9_E
P0V9_E
P0V9_E
P0V9_E
Title 
Size Document Number R e v 
Date: Sheet 
o f 
Honey badger_LSI Base Board 1B
SAS3X24R POWER_2
A3
27 71Tuesday, January 20, 2015
Honey badger_LSI Base Board
http://www.wiwynn.com
8F, 90, Sec.1, Xintai 5th Rd., Xizhi Dist.,
New Taipei City 22102, Taiwan (R.O.C.)
Title 
Size Document Number R e v 
Date: Sheet 
o f 
Honey badger_LSI Base Board 1B
SAS3X24R POWER_2
A3
27 71Tuesday, January 20, 2015
Honey badger_LSI Base Board
http://www.wiwynn.com
8F, 90, Sec.1, Xintai 5th Rd., Xizhi Dist.,
New Taipei City 22102, Taiwan (R.O.C.)
Title 
Size Document Number R e v 
Date: Sheet 
o f 
Honey badger_LSI Base Board 1B
SAS3X24R POWER_2
A3
27 71Tuesday, January 20, 2015
Honey badger_LSI Base Board
http://www.wiwynn.com
8F, 90, Sec.1, Xintai 5th Rd., Xizhi Dist.,
New Taipei City 22102, Taiwan (R.O.C.)
SC1184 
SC1U6D3V1MX-GP 
1 2
SC1183 
SC22U6D3V5MX-2GP 
1 2
SL20
MPZ2012S300AT-GP
1 2
SC1186 
SCD1U6D3V1KX-GP 
1 2
SC1197 
SCD1U6D3V1KX-GP 
1 2
SL22
MPZ2012S601AT-GP
12
SC1174 
SCD1U16V2KX-3GP 
1 2
SC1169 
SCD1U6D3V1KX-GP 
1 2
SL17
MPZ2012S300AT-GP
1 2
SC1195 
SC10U6D3V5KX-4GP 
1 2
SR832
D51R3F-2-GP
1 2
SC1173 
SCD1U16V2KX-3GP 
1 2
SC1175 
SCD1U16V2KX-3GP 
1 2
SC1193 
SCD1U6D3V1KX-GP 
1 2
SC1161 
SCD1U6D3V1KX-GP 
1 2
SC1188 
SC100U6D3V0MX-2GP 
12
8 OF 11 SU1H
SAS3X24RLC1-DB-500021106-GP
VDDK9
VDDK11
VDDK13
VDDK15
VDDK17
VDDL10
VDDL12
VDDL14
VDDL16
VDDM9
VDDM11
VDDM13
VDDM15
VDDM17
VDDN10
VDDN12
GB_VDDA2F24
GB_VDDA2G23
GB_VDDA2H24
GB_VDDA2J23
GB_VDDA2K24
GB_VDDA2L23
GB_VDDA2M20
GB_VDDA2M24
GB_VDDA2N23
GB_VDDA2P24
GB_VDDA2R23
GB_VDDA2T20
GB_VDDA2T24
GB_VDDA2U23
GB_VDDA2V17
GB_VDDA2V20
GB_VDDA2V24
GB_VDDA2W23
GB_VDDA2Y6
GB_VDDA2Y8
GB_VDDA2Y10
GB_VDDA2Y12
GB_VDDA2Y14
GB_VDDA2Y16
GB_VDDA2Y18
VDD N14
VDD N16
VDD P9
VDD P11
VDD P13
VDD P15
VDD P17
VDD R10
VDD R12
VDD R14
VDD R16
VDD T9
VDD T11
VDD T13
VDD T15
VDD T17
GB_VDDA2 Y20
GB_VDDA2 Y24
GB_VDDA2 AA21
GB_VDDA2 AA23
GB_VDDA2 AB25
GB_VDDA2 AC3
GB_VDDA2 AC5
GB_VDDA2 AC7
GB_VDDA2 AC9
GB_VDDA2 AC11
GB_VDDA2 AC13
GB_VDDA2 AC15
GB_VDDA2 AC17
GB_VDDA2 AC19
GB_VDDA2 AC21
GB_VDDA2 AC23
GB_VDDA2 AD2
GB_VDDA2 AD4
GB_VDDA2 AD6
GB_VDDA2 AD8
GB_VDDA2 AD10
GB_VDDA2 AD14
GB_VDDA2 AD16
GB_VDDA2 AD18
GB_VDDA2 AD20
XTAL_VDDA09 U7SYSPLL_VDDA09L7
GB_VDDA2K20
GB_VDDA2 AD12
SR833
D51R3F-2-GP
1 2
SC1159 
SC22U6D3V5MX-2GP 
1 2
SR836
D51R3F-2-GP
1 2
SC1163 
SCD1U6D3V1KX-GP 
1 2
SC1176 
SC100U6D3V0MX-2GP 
12
SR831
D51R3F-2-GP
1 2
SR837
10R2F-L-GP
1 2
SC1191 
SCD1U6D3V1KX-GP 
1 2
SC1200 
SC1U6D3V1MX-GP 
1 2
SC1187 
SCD1U6D3V1KX-GP 
1 2
SC1199 
SC10U6D3V5KX-4GP 
1 2
SC1162 
SCD1U6D3V1KX-GP 
1 2
SC1189 
SC22U6D3V5MX-2GP 
1 2
SC1167 
SCD1U6D3V1KX-GP 
1 2
SC1185 
SCD1U6D3V1KX-GP 
1 2
SR838
10R2F-L-GP
1 2
SC1164 
SC100U6D3V0MX-2GP 
12
SC1194 
SC22U6D3V5MX-2GP 
1 2
SC1198 
SC22U6D3V5MX-2GP 
1 2
SC1178 
SC1U6D3V1MX-GP 
1 2
SC1181 
SCD1U6D3V1KX-GP 
1 2
SC1172 
SC1U10V2KX-4-GP 
1 2
SL19
MPZ2012S300AT-GP
1 2
SC1190 
SC1U6D3V1MX-GP 
1 2
SC1158 
SC100U6D3V0MX-2GP 
12
SC1192 
SCD1U6D3V1KX-GP 
1 2
SL18
MPZ2012S300AT-GP
1 2
SC1196 
SC1U6D3V1MX-GP 
1 2
SL15
MPZ2012S300AT-GP
1 2
SR835
D51R3F-2-GP
1 2
SC1179 
SCD1U6D3V1KX-GP 
1 2
SL16
MPZ2012S300AT-GP
1 2
SC1171 
SC22U6D3V5MX-2GP 
1 2
SC1160 
SC1U6D3V1MX-GP 
1 2
SC1165 
SC22U6D3V5MX-2GP 
1 2
SC1170 
SC100U6D3V0MX-2GP 
12
SC1177 
SC22U6D3V5MX-2GP 
1 2
SC1168 
SCD1U6D3V1KX-GP 
1 2
SC1166 
SC1U6D3V1MX-GP 
1 2
SL21
MPZ2012S601AT-GP
12
SC1180 
SCD1U6D3V1KX-GP 
1 2
SR834
D51R3F-2-GP
1 2
SC1182 
SC100U6D3V0MX-2GP 
12
SC1201 
SCD1U6D3V1KX-GP 
1 2



5
5
4
4
3
3
2
2
1
1
D D
C C
B B
A A
10uF x 4 
0.1uF x 20 
10uF x 5 1nF x 5 
1nF x 5 
0.1uF x 20 
P0V9_E
P0V9_E
P1V8_E
P1V8_E
P0V9_E
P1V8_E
Title 
Size Document Number R e v 
Date: Sheet 
o f 
Honey badger_LSI Base Board 1B
SAS3X24R POWER&GND
A3
28 71Tuesday, January 20, 2015
Honey badger_LSI Base Board
http://www.wiwynn.com
8F, 90, Sec.1, Xintai 5th Rd., Xizhi Dist.,
New Taipei City 22102, Taiwan (R.O.C.)
Title 
Size Document Number R e v 
Date: Sheet 
o f 
Honey badger_LSI Base Board 1B
SAS3X24R POWER&GND
A3
28 71Tuesday, January 20, 2015
Honey badger_LSI Base Board
http://www.wiwynn.com
8F, 90, Sec.1, Xintai 5th Rd., Xizhi Dist.,
New Taipei City 22102, Taiwan (R.O.C.)
Title 
Size Document Number R e v 
Date: Sheet 
o f 
Honey badger_LSI Base Board 1B
SAS3X24R POWER&GND
A3
28 71Tuesday, January 20, 2015
Honey badger_LSI Base Board
http://www.wiwynn.com
8F, 90, Sec.1, Xintai 5th Rd., Xizhi Dist.,
New Taipei City 22102, Taiwan (R.O.C.)
SC1249 
SCD1U6D3V1KX-GP 
1 2
SC1214 
SC1KP50V2KX-1GP 
1 2
SC1226 
SCD1U6D3V1KX-GP 
1 2
SC1211 
SC1KP50V2KX-1GP 
1 2
SC1240 
SCD1U6D3V1KX-GP 
1 2
SC1241 
SCD1U6D3V1KX-GP 
1 2
SC1225 
SCD1U6D3V1KX-GP 
1 2
SC1245 
SCD1U6D3V1KX-GP 
1 2
10 OF 11 SU1J
SAS3X24RLC1-DB-500021106-GP
VSSN13
VSSN15
VSSN17
VSSN18
VSSN20
VSSN26
VSSP10
VSSP12
VSSP14
VSSP16
VSSP18
VSSP20
VSSP23
VSSR11
VSSR13
VSSR15
VSSR17
VSSR18
VSSR19
VSSR20
VSSR26
VSST10
VSST12
VSST14
VSST16
VSST18
VSST19
VSST23
VSSU10
VSSU11
VSS U12
VSS U13
VSS U14
VSS U15
VSS U16
VSS U17
VSS U18
VSS U19
VSS U20
VSS U26
VSS V1
VSS V16
VSS V18
VSS V19
VSS V23
VSS W10
VSS W11
VSS W12
VSS W13
VSS W14
VSS W15
VSS W16
VSS W17
VSS W18
VSS W19
VSS W20
VSS W26
VSS Y1
VSS Y2
VSSP3
VSSP8
VSSR6
VSSR8
VSST3
VSST8
VSSU6
VSSU8
VSSU9
VSS V2
VSS V3
VSS V6
VSS V7
VSS W4
VSS W5
VSS W6
VSS W7
VSS W8
VSS W9
SC1215 
SC1KP50V2KX-1GP 
1 2
SC1219 
SC1KP50V2KX-1GP 
1 2
SC1208 
SC10U6D3V5KX-4GP 
1 2
SC1248 
SCD1U6D3V1KX-GP 
1 2
SC1213 
SC1KP50V2KX-1GP 
1 2
SC1224 
SCD1U6D3V1KX-GP 
1 2
SC1229 
SCD1U6D3V1KX-GP 
1 2
SC1206 
SC10U6D3V5KX-4GP 
1 2
SC1236 
SCD1U6D3V1KX-GP 
1 2
SC1242 
SCD1U6D3V1KX-GP 
1 2
SC1232 
SCD1U6D3V1KX-GP 
1 2
SC1205 
SC10U6D3V5KX-4GP 
1 2
SC1231 
SCD1U6D3V1KX-GP 
1 2
SC1230 
SCD1U6D3V1KX-GP 
1 2
SC1227 
SCD1U6D3V1KX-GP 
1 2
SC1202 
SC10U6D3V5KX-4GP 
1 2
SC1221 
SCD1U6D3V1KX-GP 
1 2
SC1228 
SCD1U6D3V1KX-GP 
1 2
SC1222 
SCD1U6D3V1KX-GP 
1 2
SC1243 
SCD1U6D3V1KX-GP 
1 2
SC1254 
SCD1U6D3V1KX-GP 
1 2
SC1209 
SC10U6D3V5KX-4GP 
1 2
SC1217 
SC1KP50V2KX-1GP 
1 2
SC1252 
SCD1U6D3V1KX-GP 
1 2
SC1238 
SCD1U6D3V1KX-GP 
1 2
9 OF 11 SU1I
SAS3X24RLC1-DB-500021106-GP
VSSB3
VSSC10
VSSC12
VSSC14
VSSC16
VSSC18
VSSC20
VSSC22
VSSC24
VSSC26
VSSD3
VSSE21
VSSE22
VSSE24
VSSE25
VSSE26
VSSF20
VSSF23
VSSG11
VSSG13
VSSG16
VSSG18
VSSG20
VSSG26
VSSH19
VSSH20
VSSH23
VSSJ10
VSSJ11
VSSJ12
VSSJ13
VSS J16VSS J14
VSS J17
VSS J18
VSS J19
VSS J20
VSS J26
VSS K10
VSS K12
VSS K14
VSS K16
VSS K18
VSS K23
VSS L11
VSS L13
VSS L15
VSS L17
VSS L18
VSS L20
VSS L26
VSS M10
VSS M12
VSS M14
VSS M16
VSS M18
VSS M23
VSS N11
VSS N6
VSS N8
VSS N9
VSSC6
VSSC8
VSSF3
VSSG7
VSSG9
VSSH3
VSSJ7
VSSJ8
VSS K3
VSS K5
VSS K7
VSS K8
VSS L6
VSS L8
VSS L9
VSS M3
VSS M8
SC1207 
SC10U6D3V5KX-4GP 
1 2
SC1233 
SCD1U6D3V1KX-GP 
1 2
SC1204 
SC10U6D3V5KX-4GP 
1 2
SC1203 
SC10U6D3V5KX-4GP 
1 2
SC1223 
SCD1U6D3V1KX-GP 
1 2
SC1244 
SCD1U6D3V1KX-GP 
1 2
SC1260 
SCD1U6D3V1KX-GP 
1 2
SC1239 
SCD1U6D3V1KX-GP 
1 2
SC1237 
SCD1U6D3V1KX-GP 
1 2
SC1218 
SC1KP50V2KX-1GP 
1 2
SC1234 
SCD1U6D3V1KX-GP 
1 2
SC1257 
SCD1U6D3V1KX-GP 
1 2
SC1235 
SCD1U6D3V1KX-GP 
1 2
SC1210 
SC10U6D3V5KX-4GP 
1 2
SC1250 
SCD1U6D3V1KX-GP 
1 2
SC1247 
SCD1U6D3V1KX-GP 
1 2
SC1251 
SCD1U6D3V1KX-GP 
1 2
SC1246 
SCD1U6D3V1KX-GP 
1 2
SC1259 
SCD1U6D3V1KX-GP 
1 2
SC1216 
SC1KP50V2KX-1GP 
1 2
SC1258 
SCD1U6D3V1KX-GP 
1 2
SC1256 
SCD1U6D3V1KX-GP 
1 2
SC1255 
SCD1U6D3V1KX-GP 
1 2
SC1253 
SCD1U6D3V1KX-GP 
1 2
SC1220 
SC1KP50V2KX-1GP 
1 2
11 OF 11 SU1K
SAS3X24RLC1-DB-500021106-GP
VSSY3
VSSY4
VSSY5
VSSY7
VSSY9
VSSY11
VSSY13
VSSY15
VSSY17
VSSY19
VSSY23
VSSAA1
VSSAA22
VSSAA26
VSSAB21
VSSAB24
VSSAB26
VSSAC2
VSSAC4
VSSAC6
VSSAC8
VSSAC10
VSSAC12
VSSAC14
VSSAC16
VSSAC18
VSSAC20
VSSAC22
VSS AC24
VSS AC25
VSS AC26
VSS AD1
VSS AD22
VSS AD24
VSS AD25
VSS AD26
VSS AE1
VSS AE22
VSS AE23
VSS AE24
VSS AE25
VSS AE26
VSS AF3
VSS AF5
VSS AF7
VSS AF9
VSS AF11
VSS AF13
VSS AF17
VSS AF19
VSS AF21
VSS AF22
VSS AF25
VSS AF15
ADCTEMP_VSSA H1
VSS AD23
SC1212 
SC1KP50V2KX-1GP 
1 2



5
5
4
4
3
3
2
2
1
1
D D
C C
B B
A A
EXP UART LEVEL SHIFT 
EXP_SMART_RX_R
SAS_SMART_R_TX
SAS_SMART_R_RX
EXP_SMART_TX_R
SMART_UART_EN
SAS_R_SDBRX
SDB_TX_R
SDB_RX_R
SAS_R_SDBTX
SDB_UART_EN
SAS_SDBRX
SAS_SDBTX
SAS_SDBTX_R
SAS_SDBRX_R SAS_SDBRX
SAS_SDBTX
P3V3_STBYP1V8_E
P3V3_STBYP1V8_E
P5V_STBY
SAS_SMART_RX25 EXP_SMART_RX 52
EXP_SMART_TX 52SAS_SMART_TX25
SDB_RX25
SDB_TX25
Title 
Size Document Number R e v 
Date: Sheet 
o f 
Honey badger_LSI Base Board 1B
SAS3X24R UART LEVEL SHIFT
A3
29 71Tuesday, January 20, 2015
Honey badger_LSI Base Board
http://www.wiwynn.com
8F, 90, Sec.1, Xintai 5th Rd., Xizhi Dist.,
New Taipei City 22102, Taiwan (R.O.C.)
Title 
Size Document Number R e v 
Date: Sheet 
o f 
Honey badger_LSI Base Board 1B
SAS3X24R UART LEVEL SHIFT
A3
29 71Tuesday, January 20, 2015
Honey badger_LSI Base Board
http://www.wiwynn.com
8F, 90, Sec.1, Xintai 5th Rd., Xizhi Dist.,
New Taipei City 22102, Taiwan (R.O.C.)
Title 
Size Document Number R e v 
Date: Sheet 
o f 
Honey badger_LSI Base Board 1B
SAS3X24R UART LEVEL SHIFT
A3
29 71Tuesday, January 20, 2015
Honey badger_LSI Base Board
http://www.wiwynn.com
8F, 90, Sec.1, Xintai 5th Rd., Xizhi Dist.,
New Taipei City 22102, Taiwan (R.O.C.)
SC1300 
SCD1U16V2KX-3GP 
1 2
SR840 10KR2F-2-GP1 2
SC1299 
SCD1U16V2KX-3GP 
1 2
SR936 0R2J-2-GP 12
U186
TXS0102DCUR-1-GP
B2 1
GND 2
VCCA3
A24 A15
OE6
VCCB 7
B1 8
SR934 0R2J-2-GP 12
SCN5
JWT-CON4-S24-GP
1
2
3
4
SR938 0R2J-2-GP 12
SC1298 
SCD1U16V2KX-3GP 
1 2
SC1306 
SCD1U16V2KX-3GP 
1 2
U185
TXS0102DCUR-1-GP
B2 1
GND 2
VCCA3
A24 A15
OE6
VCCB 7
B1 8
SC1301 
SCD1U16V2KX-3GP 
1 2
SR850 0R2J-2-GP1 2
SR939 0R2J-2-GP 12
SR841 10KR2F-2-GP1 2
SR940 0R2J-2-GP 12
SR848 0R2J-2-GP1 2
SR935 0R2J-2-GP 12
SR937 0R2J-2-GP 12
SR933 0R2J-2-GP 12



5
5
4
4
3
3
2
2
1
1
D D
C C
B B
A A
ADD=1100001 (0xC2) 
450mA 
RESERVE FOR BYPASS 
SAS RE-DRIVER 
INT MINI SAS CONN 
SAS_HDD_CONN_SER_RX8_N
SAS_HDD_REDV_SER_TX7_N
REDV_I2C_SEL2B
REDV_D2_B
REDV_I2C_A1
REDV_MODE
SAS_HDD_CONN_SER_TX8_P
REDV_D1_A
SAS_HDD_REDV_SER_TX7_N
SAS_HDD_REDV_SER_RX7_P
SAS_HDD_CONN_SER_TX8_N
REDV_TX7_N
REDV_I2C_SEL1A
SAS_HDD_REDV_SER_TX8_P
SAS_HDD_REDV_SER_TX8_N
SAS_HDD_REDV_SER_RX7_N
REDV_D2_A
SAS_HDD_REDV_SER_RX8_P
REDV_I2C_A0
REDV_I2C_SEL2A
REDV_TX8_P
1.2V_REDV
REDV_I2C_A4
SAS_HDD_CONN_SER_RX7_N
REDV_RX7_N
REDV_RX8_P
SAS_HDD_REDV_SER_RX7_N
SAS_HDD_REDV_SER_RX8_P
SAS_HDD_CONN_SER_RX7_P
REDV_I2C_SCL
SAS_HDD_CONN_SER_RX8_P
REDV_RX7_P
REDV_RX8_N
SAS_HDD_REDV_SER_RX8_N
SAS_HDD_CONN_SER_TX7_N
SAS_HDD_CONN_SER_RX8_N
SAS_HDD_REDV_SER_RX7_P
SAS_HDD_REDV_SER_RX8_N
SAS_HDD_CONN_SER_RX7_P
REDV_D1_B
SAS_HDD_CONN_SER_TX8_P
REDV_PD#
SAS_HDD_REDV_SER_TX7_P
REDV_I2C_SDA
SAS_HDD_REDV_SER_TX8_P
REDV_I2C_SEL1B
SAS_HDD_CONN_SER_RX7_N
REDV_TX7_P
REDV_TX8_N
SAS_HDD_CONN_SER_TX8_NSAS_HDD_REDV_SER_TX8_N
SAS_HDD_CONN_SER_TX7_P
SAS_HDD_CONN_SER_RX8_P
SAS_HDD_CONN_SER_TX7_P
SAS_HDD_CONN_SER_TX7_N
SAS_HDD_REDV_SER_TX7_P
MINI_RX_P_20
MINI_RX_N_20
MINI_RX_P_21
MINI_RX_N_21
MINI_RX_P_22
MINI_RX_N_22
MINI_RX_P_23
MINI_RX_N_23
INT_CONN_A_SB7
INT_CONN_A_SB3
INT_CONN_A_SB2
INT_CONN_A_SB0
INT_CONN_A_SB1
INT_CONN_A_SB4
INT_CONN_A_SB5
INT_CONN_A_SB6
INTA_LED_GND
INTA_LED_BLUE_C
INTA_LED_BLUE_B
INTA_LED_RED_B
INTA_LED_RED_C
P1V26_STBY
P1V26_STBY
P3V3 P12V
P3V3_STBY
SAS_HDD_REDV_TX7_P21
SAS_HDD_REDV_TX7_N21
SAS_HDD_REDV_TX8_P21
SAS_HDD_REDV_TX8_N21
SAS_HDD_CONN_TX7_P 38
SAS_HDD_CONN_TX7_N 38
SAS_HDD_CONN_TX8_P 38
SAS_HDD_CONN_TX8_N 38
SAS_GF_EXP_RX_DP838
SAS_GF_EXP_RX_DN838
SAS_GF_EXP_RX_DP738
SAS_GF_EXP_RX_DN738
SAS_HDD_CONN_RX8_N 21
SAS_HDD_CONN_RX8_P 21
SAS_HDD_CONN_RX7_N 21
SAS_HDD_CONN_RX7_P 21
EXP_SCL_L_037
EXP_SDA_L_037
SAS_EXP2CONN_RX_N_2021
SAS_EXP2CONN_RX_P_2021
SAS_EXP2CONN_RX_P_2121
SAS_EXP2CONN_RX_N_2121
SAS_EXP2CONN_RX_P_2222
SAS_EXP2CONN_RX_N_2222
SAS_EXP2CONN_RX_P_2322
SAS_EXP2CONN_RX_N_2322
SAS_EXP2CONN_TX_P_2021
SAS_EXP2CONN_TX_N_2021
SAS_EXP2CONN_TX_N_2121
SAS_EXP2CONN_TX_P_2121
SAS_EXP2CONN_TX_N_2222
SAS_EXP2CONN_TX_P_2222
SAS_EXP2CONN_TX_P_2322
SAS_EXP2CONN_TX_N_2322
SAS_Status_LED17 23
SAS_Activity_LED16 23
Title 
Size Document Number R e v 
Date: Sheet 
o f 
Honey badger_LSI Base Board 1B
SAS3X24R MINI SAS&REDRIVER
A3
30 71Tuesday, January 20, 2015
Honey badger_LSI Base Board
http://www.wiwynn.com
8F, 90, Sec.1, Xintai 5th Rd., Xizhi Dist.,
New Taipei City 22102, Taiwan (R.O.C.)
Title 
Size Document Number R e v 
Date: Sheet 
o f 
Honey badger_LSI Base Board 1B
SAS3X24R MINI SAS&REDRIVER
A3
30 71Tuesday, January 20, 2015
Honey badger_LSI Base Board
http://www.wiwynn.com
8F, 90, Sec.1, Xintai 5th Rd., Xizhi Dist.,
New Taipei City 22102, Taiwan (R.O.C.)
Title 
Size Document Number R e v 
Date: Sheet 
o f 
Honey badger_LSI Base Board 1B
SAS3X24R MINI SAS&REDRIVER
A3
30 71Tuesday, January 20, 2015
Honey badger_LSI Base Board
http://www.wiwynn.com
8F, 90, Sec.1, Xintai 5th Rd., Xizhi Dist.,
New Taipei City 22102, Taiwan (R.O.C.)
SR885 0R2J-2-GPNOPOP1 2
SC1293 
SCD1U16V2KX-3GP 
1 2
R659
1K8R6J-GP
1 2
SC1276 SCD01U50V2KX-1GP1 2
SC1278 SCD01U50V2KX-1GP1 2
SR877 0R2J-2-GPNOPOP1 2
SC1291 
SCD1U16V2KX-3GP 
1 2
SC1290 
SCD1U16V2KX-3GP 
1 2
SC1280 SCD01U50V2KX-1GP1 2
SR892 0R2J-2-GP1 2
SR900 
4K7R2F-GP 
NOPOP 
1 2
SR869 0R2J-2-GPNOPOP1 2
SR1261
0R2J-2-GP
1 2
SR875 0R2J-2-GP1 2
SR895 0R2J-2-GP1 2
R290 
49D9R2F-GP 
NOPOP
1 2
SC1277 SCD01U50V2KX-1GP1 2
R675
1KR2F-3-GP
1 2
SR870
0R5J-5-GP
1 2
SR896 0R2J-2-GPNOPOP1 2
SR871 0R2J-2-GP1 2
SC1288 
SC10U6D3V5KX-4GP 
1 2
SR888 0R2J-2-GP1 2
SU77
PI2EQX6812ZHE-GP
NOPOP
VDD3
VDD14
VDD25
VDD30
VDD31
VDD8
VDD9
VDD36
GND 43
A0RX+ 4
A0RX- 5
A1RX+ 10
A1RX- 11
B0RX- 32B0RX+ 33
B1RX- 26B1RX+ 27
A0TX- 34A0TX+ 35
A1TX- 28A1TX+ 29
B0TX+ 6
B0TX- 7
B1TX+ 12
B1TX- 13D1_B19
D2_B16
SCL39 SDA38 PD# 37
MODE 15
NC#2 2
NC#18 18
NC#20 20
A021
A122
A417
D1_A41
D2_A40
SEL1A1
SEL2A42
SEL1B24
SEL2B23
Q22
PMBS3904-1-GP
3
1
2
SR883 0R2J-2-GP1 2
SR897 0R2J-2-GPNOPOP1 2
SR901 
4K7R2F-GP 
1 2
STP143
TPAD32-GP
1
SR868 0R2J-2-GPNOPOP1 2
TP186 TPAD32-GP1
R674
0R2J-2-GP
1 2
SC1275 SCD01U50V2KX-1GP1 2
R673
300R3F-GP
1 2
SR910 
4K7R2F-GP 
1 2
SR880 0R2J-2-GP1 2
SR906 
4K7R2F-GP 
NOPOP 
1 2
SC1289 
SC1U10V2KX-4-GP 
1 2
SR912 
4K7R2F-GP 
1 2
TP187 TPAD32-GP1
TP147 TPAD32-GP1
SR903 0R2J-2-GPNOPOP1 2
SR913 
4K7R2F-GP 
1 2
SR1271
0R2J-2-GP
1 2
R678
1KR2F-3-GP
NOPOP
1 2
SR882 0R2J-2-GPNOPOP1 2
SR902 
4K7R2F-GP 
1 2
SR905 
4K7R2F-GP 
NOPOP 
1 2
SR884 0R2J-2-GP1 2
SR908 
4K7R2F-GP 
1 2
RED 
ANODE 
COMMON CATHODE 
BLUE 
ANODE 
LED7
LED-RB-7-GP
1
2
3
SR890 0R2J-2-GPNOPOP1 2
TP148 TPAD32-GP1
SR893 0R2J-2-GPNOPOP1 2
SR889 0R2J-2-GPNOPOP1 2
CN2
AMP-CONN36-2R-GP
SIGNAL_GROUND A1
RX_0+A2
RX_0-A3
SIGNAL_GROUND A4
RX_1+A5
RX_1-A6
SIGNAL_GROUND A7
SIDEBAND_7 A8
SIDEBAND_3 A9
SIDEBAND_4 A10
SIDEBAND_5 A11
SIGNAL_GROUND A12
RX_2+A13
RX_2-A14
SIGNAL_GROUND A15
RX_3+A16
RX_3-A17
SIGNAL_GROUND A18
SIGNAL_GROUND B1
TX_0+B2
TX_0-B3
SIGNAL_GROUND B4
TX_1+B5
TX_1-B6
SIGNAL_GROUND B7
SIDEBAND_0 B8
SIDEBAND_1 B9
SIDEBAND_2 B10
SIDEBAND_6 B11
SIGNAL_GROUND B12
TX_2+B13
TX_2-B14
SIGNAL_GROUND B15
TX_3+B16
TX_3-B17
SIGNAL_GROUND B18NP1NP1
NP2NP2
37 37
38 38
39 39
40 40
41 41
42 42
SR874 0R2J-2-GPNOPOP1 2
TP188 TPAD32-GP1
SR887 0R2J-2-GP1 2
SC1274 SCD01U50V2KX-1GP1 2
R676
1KR2F-3-GP
1 2
SR891 0R2J-2-GP1 2
TP184 TPAD32-GP1
Q5
PMBS3904-1-GP
3
1
2
SR898 0R2J-2-GP1 2
SR909
4K7R2F-GP
NOPOP
1 2
SR894 0R2J-2-GP1 2
SR881 0R2J-2-GPNOPOP1 2
SR879 0R2J-2-GP1 2
SR907 
4K7R2F-GP 
NOPOP 
1 2
SR911 
4K7R2F-GP 
1 2
SR878 0R2J-2-GPNOPOP1 2
TP189 TPAD32-GP1
SR876 0R2J-2-GP1 2
TP185 TPAD32-GP1SC1279 SCD01U50V2KX-1GP1 2
SR904 
4K7R2F-GP 
NOPOP 
1 2
SR872 0R2J-2-GP1 2
SC1281 SCD01U50V2KX-1GP1 2
SR886 0R2J-2-GPNOPOP1 2
R677
1KR2F-3-GP
NOPOP
1 2
SR899 0R2J-2-GP1 2
SC1292 
SCD1U16V2KX-3GP 
1 2
SR873 0R2J-2-GPNOPOP1 2



5
5
4
4
3
3
2
2
1
1
D D
C C
B B
A A
AND GATE 
ENCLOSURE STATUS_LED 
Power and identify blink LED 
LED_PWR_N_R
ENCLO_LED_BLUE_OUT ENCLO_LED_RED_G
ENCLO_LED_RED_D
ENCLO_LED_RED_D1
ENCLO_LED_RED_R
BMC_ID_LED_R
BMC_ENCLOSURE_LED_R
HB_OUT_R
LED_PWR_N_ON
P3V3_STBY
P5V_STBY
P3V3_STBY
P5V_STBY
HB_OUT32,38
BMC_ID_LED43
PMU_PLTRST_N13,18,33,40,42,44,50,52
BMC_ENCLOSURE_LED44
LED_DR_LED141,44
Title 
Size Document Number R e v 
Date: Sheet 
o f 
Honey badger_LSI Base Board 1B
POWER/ENCLOUSRE LED
A3
31 71Tuesday, January 20, 2015
Honey badger_LSI Base Board
http://www.wiwynn.com
8F, 90, Sec.1, Xintai 5th Rd., Xizhi Dist.,
New Taipei City 22102, Taiwan (R.O.C.)
Title 
Size Document Number R e v 
Date: Sheet 
o f 
Honey badger_LSI Base Board 1B
POWER/ENCLOUSRE LED
A3
31 71Tuesday, January 20, 2015
Honey badger_LSI Base Board
http://www.wiwynn.com
8F, 90, Sec.1, Xintai 5th Rd., Xizhi Dist.,
New Taipei City 22102, Taiwan (R.O.C.)
Title 
Size Document Number R e v 
Date: Sheet 
o f 
Honey badger_LSI Base Board 1B
POWER/ENCLOUSRE LED
A3
31 71Tuesday, January 20, 2015
Honey badger_LSI Base Board
http://www.wiwynn.com
8F, 90, Sec.1, Xintai 5th Rd., Xizhi Dist.,
New Taipei City 22102, Taiwan (R.O.C.)
R5774
330R1210J-GP
1 2
LED5
LED-B-77-GP-U3
A K
Q13
2N7002A-7-GP
G
SD
U38
SN74LVC1G08DCKR-GP
B2
A1
GND3 Y 4
VCC 5
C269
SCD1U16V2KX-3GP
1 2
R543
330R1210J-GP
1 2
LED4
LED-B-77-GP-U3
A K
Q6
2N7002A-7-GPG
SD
R78900R2J-2-GP NOPOP1 2
R544
1KR2F-3-GP
12
Q9
2N7002A-7-GP
G
SD
R532
1KR2F-3-GP
1 2
R683
0R2J-2-GP
12
R78890R2J-2-GP 1 2
R305
0R2J-2-GP
12
R78920R2J-2-GP NOPOP1 2
R529
1KR2F-3-GP
NOPOP
1 2



5
5
4
4
3
3
2
2
1
1
D D
C C
B B
A A
2.8V 
0.5V 
2.8V 
0.5V 
Heart Beat Circuitry 
DIVIDER 1_IN
DIVIDER 2_IN
HB_A_IN
INVERTER_G2
INVERTER_G1
HB_A_OUT
DIVIDER 1_IN_EXP
DIVIDER 2_IN_EXP
HB_A_IN_EXP
INVERTER_G1_EXP
INVERTER_G2_EXP
HB_A_OUT_EXP
EXP_BMC_HB_LED_R
HB_OUT
EXP_BMC_HB_LED_D
P3V3_STBY
P3V3_STBY
P3V3_STBY
P3V3_STBY
P3V3_STBY
P3V3_STBY
P3V3_STBY
P3V3_STBY
P3V3_STBY
P3V3_STBY
P3V3_STBY
P3V3_STBY
P3V3_STBY
HB_EXP_TO_BMC 44
EXP_HB23
HB_OUT 31,38
HB_OUT_BMC44
Title 
Size Document Number R e v 
Date: Sheet 
o f 
Honey badger_LSI Base Board 1B
HEARTBEAT CIRCUITRY
A3
32 71Tuesday, January 20, 2015
Honey badger_LSI Base Board
http://www.wiwynn.com
8F, 90, Sec.1, Xintai 5th Rd., Xizhi Dist.,
New Taipei City 22102, Taiwan (R.O.C.)
Title 
Size Document Number R e v 
Date: Sheet 
o f 
Honey badger_LSI Base Board 1B
HEARTBEAT CIRCUITRY
A3
32 71Tuesday, January 20, 2015
Honey badger_LSI Base Board
http://www.wiwynn.com
8F, 90, Sec.1, Xintai 5th Rd., Xizhi Dist.,
New Taipei City 22102, Taiwan (R.O.C.)
Title 
Size Document Number R e v 
Date: Sheet 
o f 
Honey badger_LSI Base Board 1B
HEARTBEAT CIRCUITRY
A3
32 71Tuesday, January 20, 2015
Honey badger_LSI Base Board
http://www.wiwynn.com
8F, 90, Sec.1, Xintai 5th Rd., Xizhi Dist.,
New Taipei City 22102, Taiwan (R.O.C.)
SC1310 
SC10U6D3V5KX-4GP 
NOPOP 
1 2
+
K
U36B
LM393ADR-1-GP
5
6
7
8 4
+
K
U41B
LM393ADR-1-GP
5
6
7
8 4
+
K
U41A
LM393ADR-1-GP
3
2
1
8 4
R500
1KR2F-3-GP
1 2
SR707 
150R2F-1-GP 
1 2
C263
SCD1U16V2KX-3GP
1 2
R479
51R2010F-GP
1 2
R485
1KR2F-3-GP
1 2
R501
1KR2F-3-GP
1 2
R477
4K7R2F-GP
1 2
R498
0R2J-2-GP
NOPOP
1 2
R478
2MR2F-GP
1 2
C264
SCD1U16V2KX-3GP
1 2
+
K
U36A
LM393ADR-1-GP
3
2
1
8 4
Q21
2N7002A-7-GP
G
SD
R482
0R2J-2-GP
1 2
R495
51R2010F-GP
NOPOP
1 2
Q10
2N7002DW-7F-GP
1
2
3 4
5
6
R494
2MR2F-GP
1 2
R499
0R2J-2-GP
1 2
R481
200R3F-GP
1 2
R484
1KR2F-3-GP
1 2
Q18
2N7002DW-7F-GP
NOPOP
1
2
3 4
5
6
R496
10KR2F-2-GP
NOPOP
1 2
R493
4K7R2F-GP
1 2
R483
0R2J-2-GP
NOPOP
1 2
R480
10KR2F-2-GP
1 2
C305 
SC1U10V3KX-4GP-U 
1 2
SC1309 
SC10U6D3V5KX-4GP 
NOPOP 
1 2
C304 
SC1U10V3KX-4GP-U 
1 2
R497
200R3F-GP
1 2
SLED28
LED-YG-51-GP
A K



5
5
4
4
3
3
2
2
1
1
D D
C C
B B
A A
SLOT ID 
TP_MSB_A34_CPU_SATA_RX_N
PCIE_10G_CPU_TX2_P
PCIE_10G_CPU_TX2_N
PCIE_10G_CPU_TX3_P
PCIE_10G_CPU_TX3_N
PCIE_10G_CPU_TX0_P
PCIE_10G_CPU_TX0_N
PCIE_10G_CPU_TX1_P
PCIE_10G_CPU_TX1_N
USB_P0_DP
CPU_TXD
CPU_RXD
USB_P0_DN
SVR_ID3
PRSNT_MSB_A1
SVR_ID0
SVR_ID2
SVR_ID1
PCIE_10G_CPU_RX3_P
PCIE_10G_CPU_RX3_N
PCIE_10G_CPU_RX2_P
PCIE_10G_CPU_RX2_N
PCIE_10G_CPU_RX1_P
PCIE_10G_CPU_RX1_N
PCIE_10G_CPU_RX0_P
PCIE_10G_CPU_RX0_N
SVR_ID2
SVR_ID3
BMC_MSB_I2C_E_ALERT_#
SVR_ID1
TP_MSB_A33_CPU_SATA_RX_P
CLK_100M_PCIE_SAS_C_P
TP_MSB_B31_CPU_SATA_TX_P
TP_MSB_B32_CPU_SATA_TX_N
CLK_100M_PCIE_SAS_C_N
PMU_PLTRST#
CPU_RESET_N_R
PRSNT_MSB_A1
TP_MSB_A41
TP_MSB_A46_GBE_RX_N
TP_MSB_A45_GBE_RX_P
NIC_SMBUS_SCL
NIC_SMBUS_SDA
TP_MSB_B47_CPU_GBE_TX_P
TP_MSB_B47_CPU_GBE_TX_N
TP_MSB_B40
NIC_SMBUS_ALERT_N
PRSNT_MSB_B81
SVR_ID0
PMU_PLTRST#
PMU_PLTRST#
PRSNT_MSB_B81
PRSNT_MSB_AND_1
P12V_MSB
P12V_MSB
P3V3_STBY
P12V_MSB
P3V3_STBYP3V3_STBY P3V3_STBY
P3V3_STBY
P3V3_STBY
P12V_MSB
P3V3
P3V3_STBY
P3V3_STBY
PCIE_10G_CPU_TX1_P40
CPU_RXD 52
PCIE_10G_CPU_TX1_N40
PCIE_10G_CPU_TX3_P40
PCIE_10G_CPU_TX3_N40
PCIE_SAS_CPU_TX_P011
PCIE_10G_CPU_TX2_N40
PCIE_SAS_CPU_TX_N011
PCIE_10G_CPU_TX2_P40
PCIE_SAS_CPU_RX_P0 11
PCIE_SAS_CPU_RX_N0 11
BMC_MBC_I2C_E_SCL40,42
BMC_MBC_I2C_E_SDA40,42
PCIE_SAS_CPU_TX_P111
PCIE_SAS_CPU_TX_N111
PCIE_SAS_CPU_TX_N211
PCIE_SAS_CPU_TX_P211
CPU_RESET_N53
PCIE_SAS_CPU_TX_P311
PCIE_SAS_CPU_TX_N311
PCIE_SAS_CPU_TX_N411
PCIE_SAS_CPU_TX_P411
USB_P0_DP50
PCIE_SAS_CPU_TX_P511
PCIE_SAS_CPU_TX_N511
PCIE_SAS_CPU_TX_P611
PCIE_SAS_CPU_TX_N611
USB_P0_DN50
PCIE_SAS_CPU_TX_N711
PCIE_SAS_CPU_TX_P711
PCIE_10G_CPU_RX0_P 40
CLK_100M_PCIE_SAS_C_N 11
CLK_100M_PCIE_SAS_C_P 11
PCIE_10G_CPU_RX0_N 40
PCIE_10G_CPU_RX1_P 40
PCIE_10G_CPU_RX1_N 40
PCIE_10G_CPU_RX2_P 40
PCIE_10G_CPU_RX2_N 40
PCIE_10G_CPU_RX3_P 40
PCIE_10G_CPU_RX3_N 40
CLK_100M_CLKBUFF_ENET1_DN40
PCIE_SAS_CPU_RX_N1 11
PCIE_SAS_CPU_RX_P1 11
PCIE_SAS_CPU_RX_P2 11
PCIE_SAS_CPU_RX_N2 11
CLK_100M_CLKBUFF_ENET1_DP40
BMC_MSB_I2C_E_ALERT_#42
CPU_TXD 52
PCIE_SAS_CPU_RX_N3 11
PCIE_SAS_CPU_RX_P3 11
PCIE_SAS_CPU_RX_P4 11
PCIE_SAS_CPU_RX_N4 11
PCIE_10G_CPU_TX0_P40
PCIE_SAS_CPU_RX_N5 11
PCIE_SAS_CPU_RX_P5 11
PMU_PWRBTN_N53
PCIE_SAS_CPU_RX_P6 11
PCIE_SAS_CPU_RX_N6 11
PCIE_10G_CPU_TX0_N40
PCIE_SAS_CPU_RX_P7 11
PCIE_SAS_CPU_RX_N7 11
NIC_SMBUS_SCL42
NIC_SMBUS_SDA42
NIC_SMBUS_ALERT_N 42
SVR_ID0 44
PMU_PLTRST_N 13,18,31,40,42,44,50,52
CLK_100M_CLKBUFF_ENET2_DN 40
CLK_100M_CLKBUFF_ENET2_DP 40
PRSNT_MSB_AND_1 40
Title 
Size Document Number R e v 
Date: Sheet 
o f 
Honey badger_LSI Base Board 1B
x16 PCIe CONN FOR uSERVER
A3
33 71Tuesday, January 20, 2015
Honey badger_LSI Base Board
http://www.wiwynn.com
8F, 90, Sec.1, Xintai 5th Rd., Xizhi Dist.,
New Taipei City 22102, Taiwan (R.O.C.)
Title 
Size Document Number R e v 
Date: Sheet 
o f 
Honey badger_LSI Base Board 1B
x16 PCIe CONN FOR uSERVER
A3
33 71Tuesday, January 20, 2015
Honey badger_LSI Base Board
http://www.wiwynn.com
8F, 90, Sec.1, Xintai 5th Rd., Xizhi Dist.,
New Taipei City 22102, Taiwan (R.O.C.)
Title 
Size Document Number R e v 
Date: Sheet 
o f 
Honey badger_LSI Base Board 1B
x16 PCIe CONN FOR uSERVER
A3
33 71Tuesday, January 20, 2015
Honey badger_LSI Base Board
http://www.wiwynn.com
8F, 90, Sec.1, Xintai 5th Rd., Xizhi Dist.,
New Taipei City 22102, Taiwan (R.O.C.)
Q7
2N7002A-7-GP
G
SD
C290 SCD1U25V2KX-2-GP1 2
C289 SCD1U25V2KX-2-GP1 2
C291 SCD1U25V2KX-2-GP1 2
C258 
SC1U25V3KX-GP 
1 2
C295 SCD1U25V2KX-2-GP1 2
CN8
PCISLT164-44-GP
A1
A2
A3
A4
A5
A6
A7
A8
A9
A10
A11
A12
A13
A14
A15
A16
A17
A18
A19
A20
A21
A22
A23
A24
A25
A26
A27
A28
A29
A30
A31
A32
A33
A34
A35
A36
A37
A38
A39
A40
A41
A42
A43
A44
A45
A46
A47
A48
A49
A50
A51
A52
A53
A54
A55
A56
A57
A58
A59
A60
A61
A62
A63
A64
A65
A66
A67
A68
A69
A70
A71
A72
A73
A74
A75
A76
A77
A78
A79
A80
A81
A82
B1
B2
B3
B4
B5
B6
B7
B8
B9
B10
B11
B12
B13
B14
B15
B16
B17
B18
B19
B20
B21
B22
B23
B24
B25
B26
B27
B28
B29
B30
B31
B32
B33
B34
B35
B36
B37
B38
B39
B40
B41
B42
B43
B44
B45
B46
B47
B48
B49
B50
B51
B52
B53
B54
B55
B56
B57
B58
B59
B60
B61
B62
B63
B64
B65
B66
B67
B68
B69
B70
B71
B72
B73
B74
B75
B76
B77
B78
B79
B80
B81
B82
NP1
NP2
C292 SCD1U25V2KX-2-GP1 2 R521
10KR2F-2-GP
12
R525
10KR2F-2-GP1 2
R17
100R2F-L1-GP-U
NOPOP
1 2
C293 SCD1U25V2KX-2-GP1 2
R15
100R2F-L1-GP-U
1 2
R14
10KR2F-2-GP
NOPOP
12
R19
0R2J-2-GP
1 2
C256 
SCD1U25V2KX-2-GP 
1 2
C329
SCD1U25V2KX-2-GP
1 2
C261 
SCD1U25V2KX-2-GP 
1 2
C294 SCD1U25V2KX-2-GP1 2
PR170
100KR2F-L1-GP
1 2
R524
1KR2F-3-GP
1 2
TP1491
R16
100R2F-L1-GP-U
1 2
TP157 1
C275 SCD1U25V2KX-2-GP1 2
R18
100R2F-L1-GP-U
NOPOP
1 2
C257 
SC22U25V5MX-GP 
1 2
R11
10KR2F-2-GP
NOPOP
12
C262 
SCD1U25V2KX-2-GP 
1 2
R12
10KR2F-2-GP
NOPOP
12
C259 
SCD1U25V2KX-2-GP 
1 2
C253 
SC1U25V3KX-GP 
1 2
Q8
2N7002A-7-GPG
SD
R21
10KR2F-2-GP
12
R13
10KR2F-2-GP
NOPOP
12
C270 
SC22U25V5MX-GP 
1 2
U32
SN74LVC1G07DCKRG4-2-GP
GND3 A2 NC#11 VCC 5
Y 4



5
5
4
4
3
3
2
2
1
1
D D
C C
B B
A A
EXT miniSAS CONN 
CAGE 
SAS_EXT_CONN_RX19_N
SAS_EXT_CONN_RX16_N
SAS_EXT_CONN_RX18_N
SAS_EXT_CONN_RX17_P
SAS_EXT_CONN_RX17_N
SAS_EXT_CONN_RX18_P
SAS_EXT_CONN_RX19_P
SAS_EXT_CONN_RX16_P
IOC_SAS_RX_N611
IOC_SAS_RX_P611
IOC_SAS_RX_P711
IOC_SAS_RX_N711
IOC_SAS_RX_N511
IOC_SAS_RX_P511
IOC_SAS_RX_P411
IOC_SAS_RX_N411
IOC_RAID_TX_P5 11
IOC_RAID_TX_N5 11
IOC_RAID_TX_P6 11
IOC_RAID_TX_N6 11
IOC_RAID_TX_N7 11
IOC_RAID_TX_P7 11
IOC_RAID_TX_P4 11
IOC_RAID_TX_N4 11
Title 
Size Document Number R e v 
Date: Sheet 
o f 
Honey badger_LSI Base Board 1B
EXT MINI_SAS CONN
A3
34 71Tuesday, January 20, 2015
Honey badger_LSI Base Board
http://www.wiwynn.com
8F, 90, Sec.1, Xintai 5th Rd., Xizhi Dist.,
New Taipei City 22102, Taiwan (R.O.C.)
Title 
Size Document Number R e v 
Date: Sheet 
o f 
Honey badger_LSI Base Board 1B
EXT MINI_SAS CONN
A3
34 71Tuesday, January 20, 2015
Honey badger_LSI Base Board
http://www.wiwynn.com
8F, 90, Sec.1, Xintai 5th Rd., Xizhi Dist.,
New Taipei City 22102, Taiwan (R.O.C.)
Title 
Size Document Number R e v 
Date: Sheet 
o f 
Honey badger_LSI Base Board 1B
EXT MINI_SAS CONN
A3
34 71Tuesday, January 20, 2015
Honey badger_LSI Base Board
http://www.wiwynn.com
8F, 90, Sec.1, Xintai 5th Rd., Xizhi Dist.,
New Taipei City 22102, Taiwan (R.O.C.)
C135 SCD01U50V2KX-1GP1 2
CN4
MLX-CON7-20-GP
NP1
NP2
Z5
Z6
Z7
Z1 Z2
Z3Z4
C132 SCD01U50V2KX-1GP1 2
CN1
MLX-CONN26-GP
RX_0+A2
RX_0-A3
RX_1+A5
RX_1-A6
RX_2+A8
RX_2-A9
RX_3+A11
RX_3-A12
TX_0+ B2
TX_0- B3
TX_1+ B5
TX_1- B6
TX_2+ B8
TX_2- B9
TX_3+ B11
TX_3- B12
SIGNAL_GROUND A1
SIGNAL_GROUND A4
SIGNAL_GROUND A7
SIGNAL_GROUND A10
SIGNAL_GROUND A13
SIGNAL_GROUND B1
SIGNAL_GROUND B4
SIGNAL_GROUND B7
SIGNAL_GROUND B10
SIGNAL_GROUND B13
NP1NP1 NP2NP2
C130 SCD01U50V2KX-1GP1 2
C131 SCD01U50V2KX-1GP1 2
C134 SCD01U50V2KX-1GP1 2
C136 SCD01U50V2KX-1GP1 2
C129 SCD01U50V2KX-1GP1 2
C133 SCD01U50V2KX-1GP1 2



5
5
4
4
3
3
2
2
1
1
D D
C C
B B
A A
BLANK 
Title 
Size Document Number Rev 
Date: Sheet o f 
Honey badger_LSI Base Board 1B
BLANK
A2
35 71Tuesday, January 20, 2015
Honey badger_LSI Base Board
http://www.wiwynn.com
8F, 90, Sec.1, Xintai 5th Rd., Xizhi Dist.,
New Taipei City 22102, Taiwan (R.O.C.)
Title 
Size Document Number Rev 
Date: Sheet o f 
Honey badger_LSI Base Board 1B
BLANK
A2
35 71Tuesday, January 20, 2015
Honey badger_LSI Base Board
http://www.wiwynn.com
8F, 90, Sec.1, Xintai 5th Rd., Xizhi Dist.,
New Taipei City 22102, Taiwan (R.O.C.)
Title 
Size Document Number Rev 
Date: Sheet o f 
Honey badger_LSI Base Board 1B
BLANK
A2
35 71Tuesday, January 20, 2015
Honey badger_LSI Base Board
http://www.wiwynn.com
8F, 90, Sec.1, Xintai 5th Rd., Xizhi Dist.,
New Taipei City 22102, Taiwan (R.O.C.)



5
5
4
4
3
3
2
2
1
1
D D
C C
B B
A A
BMC_JTAG_L_EN
BMC_JTAG_L_EN
EXP_TDO_EN
JTAG_EXP_R_TDO
JTAG_IOC_L_TDI_R
JTAG_IOC_TDO_L
JTAG_DT
BMC_JTAG_L_EN
JTAG_DT
JTAG_BMC_TDI
JTAG_BMC_TMS
JTAG_IOC_TDO_L
BMC_JTAG_L_ENJTAG_BMC_TCK
JTAG_BMC_TRST_N
P3V3_STBY
P1V8_STBY
P3V3_STBY
P3V3_STBY
P1V8_STBY
P1V8_STBY
P3V3_STBY
P3V3_STBY
P1V8_STBY
P3V3_STBY
P3V3_STBY
P3V3_STBY
P3V3_STBY
JTAG_BMC_TRST_N44
JTAG_BMC_TMS44
JTAG_BMC_TCK44
JTAG_BMC_TDO44
JTAG_EXP_IOC_RST 13,25
JTAG_EXP_IOC_TMS 13,25
JTAG_EXP_IOC_TCK 13,25
JTAG_BMC_L_TDO 25
BMC_JTAG_L_EN44
JTAG_EXP_TDO25
JTAG_IOC_L_TDI 13
JTAG_IOC_TDO13
JTAG_BMC_TDI 44
BMC_JTAG_L42
JTAG_BMC_TMS44
JTAG_BMC_TCK44
JTAG_BMC_TRST_N 44 Title 
Size Document Number R e v 
Date: Sheet 
o f 
Honey badger_LSI Base Board 1B
JTAG BUNDARY SCAN
A3
36 71Tuesday, January 20, 2015
Honey badger_LSI Base Board
http://www.wiwynn.com
8F, 90, Sec.1, Xintai 5th Rd., Xizhi Dist.,
New Taipei City 22102, Taiwan (R.O.C.)
Title 
Size Document Number R e v 
Date: Sheet 
o f 
Honey badger_LSI Base Board 1B
JTAG BUNDARY SCAN
A3
36 71Tuesday, January 20, 2015
Honey badger_LSI Base Board
http://www.wiwynn.com
8F, 90, Sec.1, Xintai 5th Rd., Xizhi Dist.,
New Taipei City 22102, Taiwan (R.O.C.)
Title 
Size Document Number R e v 
Date: Sheet 
o f 
Honey badger_LSI Base Board 1B
JTAG BUNDARY SCAN
A3
36 71Tuesday, January 20, 2015
Honey badger_LSI Base Board
http://www.wiwynn.com
8F, 90, Sec.1, Xintai 5th Rd., Xizhi Dist.,
New Taipei City 22102, Taiwan (R.O.C.)
R573
10KR2F-2-GP1 2
C90 
SCD1U16V2KX-3GP 
1 2
R546
10KR2F-2-GP1 2
U178
SNLVC1G126DCKR-GP
OE1
A2
GND3 Y 4
VCC 5
U181
SN74AVC4T774RGYR-GP
A13
A24
A35
A46
DIR3 7
DIR4 8
OE#9
VCCA16 VCCB 15
B1 14
B2 13
B3 12
B4 11
GND10
DIR1 1
DIR2 2
GND17
C84 
SCD1U16V2KX-3GP 
1 2
R5750R2J-2-GP 1 2
R563
10KR2F-2-GP1 2
Q16
2N7002A-7-GP
G
SD
R561
10KR2F-2-GP
NOPOP
1 2
C89 
SCD1U16V2KX-3GP 
1 2
U182
74AVC1T45DCKR-GP
NOPOP
VCCA 1
GND12
A1 3B14
DIR 5
VCCB6
U179
SNLVC1G126DCKR-GP
OE1
A2
GND3 Y 4
VCC 5
C85 
SCD1U16V2KX-3GP 
1 2
TP1651
C87 
SCD1U16V2KX-3GP 
1 2
C86 
SCD1U16V2KX-3GP 
1 2
CN7
AMP-CONN10D-3-GP
NOPOP
1
3
5
7
9
2
4
6
8
10
NP1
NP2
Q17
2N7002A-7-GP
G
SD
R577
10KR2F-2-GP1 2
C88 
SCD1U16V2KX-3GP 
1 2
R581
4K7R2F-GP
12
R5740R2J-2-GP 1 2



5
5
4
4
3
3
2
2
1
1
D D
C C
B B
A A
ADD=01000000 (0x40) 
BMC_I2C TO GPIO 
 HDD PRESENT 
RESERVE HDD POWER BYPASS 
HDD POWER BUS SWITCH 
ADD=01010010 (0x52) 
EXP_I2C TO GPIO 
  HDD POWER 
ADD=11000000 (0xC0) 
EXP_I2C TO GPIO 
 HDD FAULT LED 
RESERVE 
BASE BOARD MATED 
ENABLE BUS SWITCH 
HDD FAULT LED BUS SWITCH 
RESERVE HDD LED BYPASS 
BMC_IOEXP_SDA_10
BMC_IOEXP_SCL_10
PRE_SDA
PRE_SCL
BMC_IOEXP_SDA_10
HDD_PRE_IO_INT_N
I2C_IO_EXP_RESET#_PRST
SAS_HDD_PWR8
SAS_HDD_PWR5
HDD_PWR_IO_INT_N
SAS_HDD_PWR6
SAS_HDD_PWR7
I2C_IO_EXP_RESET#_PWR
SAS_HDD_PWR12
SAS_HDD_PWR3
SAS_HDD_PWR10
SAS_HDD_PWR4
SAS_HDD_PWR11
SAS_HDD_PWR5
SAS_HDD_PWR12
SAS_HDD_PWR6
SAS_HDD_PWR13
SAS_HDD_PWR0
SAS_HDD_PWR1
PCIe_MATED#
SAS_HDD_PWR0
SAS_HDD_PWR7
SAS_HDD_PWR14
SAS_HDD_PWR8
SAS_HDD_PWR15
SAS_HDD_PWR9
SAS_HDD_PWR1
SAS_HDD_PWR2
SAS_HDD_PWR1
SAS_HDD_PWR2
SAS_HDD_PWR3
SAS_HDD_PWR0
SAS_HDD_PWR4
PCIe_MATED#_AB
SAS_HDD_PWR9
SAS_HDD_PWR13
SAS_HDD_PWR14
PCIe_MATED#_AB
BMC_IOEXP_SCL_10
BMC_IOEXP_SDA_10
SAS_HDD_PWR10
SAS_HDD_PWR15
SAS_HDD_PWR11
BMC_I2C10_EN
SAS_HDD_PWR2
SAS_HDD_PWR3
SAS_HDD_PWR4
SAS_HDD_PWR5
SAS_HDD_PWR6
SAS_HDD_PWR7
SAS_HDD_PWR8
SAS_HDD_PWR9
SAS_HDD_PWR10
SAS_HDD_PWR11
SAS_HDD_PWR12
SAS_HDD_PWR13
SAS_HDD_PWR14
SAS_HDD_PWR15
HDD_PWR_IO_INT_N
HDD_PRE_IO_INT_N
HDD_PRE_IO_INT_N
EXP_SCL_0
EXP_SDA_0
IO_EXP_HDD_PWR_A1
IO_EXP_HDD_PWR_A2
IO_EXP_HDD_PWR_A3
IO_EXP_HDD_PWR_A0
IO_EXP_HDD_FAULT_A0
IO_EXP_HDD_PRE_A1
IO_EXP_HDD_PRE_A2
IO_EXP_HDD_PRE_A3
IO_EXP_HDD_PRE_A0
IO_EXP_HDD_PWR_A0
IO_EXP_HDD_PWR_A1
IO_EXP_HDD_PWR_A2
IO_EXP_HDD_PWR_A3
IO_EXP_HDD_PRE_A0
IO_EXP_HDD_PRE_A1
IO_EXP_HDD_PRE_A2
IO_EXP_HDD_PRE_A3
PWR_SDA
PWR_SCL
BMC_IOEXP_SCL_10
IO_EXP_HDD_FAULT_A2
IO_EXP_HDD_FAULT_A1
SAS_HDD_LED_0
IO_EXP_HDD_FAULT_A0
IO_EXP_HDD_FAULT_A1
IO_EXP_HDD_FAULT_A2
EXP_I2C_VREF_4
EXP_SCL_L_0
EXP_SDA_L_0
FAULT_SCL
FAULT_SDA
I2C_IO_EXP_RESET#_FLT
SAS_FAULT_LED0
SAS_FAULT_LED1
SAS_FAULT_LED2
SAS_FAULT_LED3
SAS_FAULT_LED4
SAS_FAULT_LED5
SAS_FAULT_LED6
SAS_FAULT_LED7
SAS_FAULT_LED8
SAS_FAULT_LED9
SAS_FAULT_LED10
SAS_FAULT_LED11
SAS_FAULT_LED12
SAS_FAULT_LED13
SAS_FAULT_LED14
SAS_FAULT_LED15
MATED#
PRSNT_AND_3
PCIe_MATED#
PRSNT_AND_1
MATED#
PCIe_MATED#
SAS_HDD_LED_0
PCIe_MATED#_LED_CD
PCIe_MATED#_LED_CD
SAS_HDD_LED_1
SAS_HDD_LED_2
SAS_HDD_LED_3
SAS_HDD_LED_4
SAS_HDD_LED_5
SAS_HDD_LED_6
SAS_HDD_LED_7
SAS_HDD_LED_8
SAS_HDD_LED_9
SAS_HDD_LED_10
SAS_HDD_LED_11
SAS_HDD_LED_12
SAS_HDD_LED_13
SAS_HDD_LED_14
SAS_HDD_LED_15
SAS_HDD_LED_1
SAS_HDD_LED_2
SAS_HDD_LED_3
SAS_HDD_LED_4
SAS_HDD_LED_5
SAS_HDD_LED_6
SAS_HDD_LED_7
SAS_HDD_LED_8
SAS_HDD_LED_9
SAS_HDD_LED_10
SAS_HDD_LED_11
SAS_HDD_LED_12
SAS_HDD_LED_13
SAS_HDD_LED_14
SAS_HDD_LED_15
SAS_HDD_LED_0
SAS_HDD_LED_1
SAS_HDD_LED_2
SAS_HDD_LED_3
SAS_HDD_LED_4
SAS_HDD_LED_5
SAS_HDD_LED_6
SAS_HDD_LED_7
SAS_HDD_LED_8
SAS_HDD_LED_9
SAS_HDD_LED_10
SAS_HDD_LED_11
SAS_HDD_LED_12
SAS_HDD_LED_13
SAS_HDD_LED_14
SAS_HDD_LED_15
EXP_SCL_L_0
EXP_SDA_L_0
P1V8_E
P1V8_E
P1V8_E
P3V3_STBY
P3V3_STBY
P3V3_STBY
P3V3_STBY
P1V8_E
P3V3_STBY
P3V3_STBY
P3V3_STBY
P3V3_STBY
P1V8_E
P1V8_E
P3V3_STBY
P3V3_STBY
P3V3_STBY
P3V3_STBY
P1V8_E
P3V3_STBY
P3V3_STBY
P3V3_STBY
P3V3_STBY
P3V3_STBY
P3V3_STBY
P3V3_STBY
P3V3_STBY
SAS_HDD_PRE9 23,38
SAS_HDD_PRE10 23,38
SAS_HDD_PRE11 23,38
I2C_IO_EXP_RESET#44
SAS_HDD_PRE8 23,38
SAS_HDD_PRE023,38
SAS_HDD_PRE12 23,38
SAS_HDD_PWR7_PCIe 38
SAS_HDD_PWR8_PCIe 38
SAS_HDD_PWR9_PCIe 38
SAS_HDD_PWR5_PCIe 38
SAS_HDD_PWR6_PCIe 38
SAS_HDD_PWR1_PCIe 38
SAS_HDD_PWR2_PCIe 38
SAS_HDD_PWR3_PCIe 38
SAS_HDD_PWR4_PCIe 38
SAS_HDD_PWR0_PCIe 38
SAS_HDD_PWR10_PCIe 38
SAS_HDD_PWR11_PCIe 38
SAS_HDD_PWR12_PCIe 38
SAS_HDD_PWR13_PCIe 38
SAS_HDD_PWR14_PCIe 38
SAS_HDD_PWR15_PCIe 38
SAS_HDD_PWR10_PCIe 38
SAS_HDD_PWR13_PCIe 38
SAS_HDD_PWR12_PCIe 38
SAS_HDD_PWR11_PCIe 38
SAS_HDD_PWR15_PCIe 38
SAS_HDD_PWR14_PCIe 38
SAS_HDD_PWR9_PCIe 38
SAS_HDD_PWR8_PCIe 38
SAS_HDD_PWR7_PCIe 38
SAS_HDD_PWR1_PCIe 38
SAS_HDD_PWR6_PCIe 38
SAS_HDD_PWR5_PCIe 38
SAS_HDD_PWR4_PCIe 38
SAS_HDD_PWR3_PCIe 38
SAS_HDD_PWR2_PCIe 38
SAS_HDD_PWR0_PCIe 38
HDD_PWR_RESET_N23
SAS_HDD_PRE13 23,38
SAS_HDD_PRE223,38
SAS_HDD_PRE14 23,38
SAS_HDD_PRE323,38
SAS_HDD_PRE15 23,38
BMC_I2C_SCL_10 41,42,54,55
BMC_I2C_SDA_10 41,42,54,55
SAS_HDD_PRE423,38
SAS_HDD_PRE523,38
I2C_IO_EXP_RESET#44
SAS_HDD_PRE623,38
SAS_HDD_PRE723,38
SAS_HDD_PRE123,38
EXP_HDD_PRE_INT_N23
BMC_HDD_PRE_INT_N44
EXP_SCL_022
EXP_SDA_022
EXP_SCL_0 22
EXP_SDA_0 22
BMC_I2C_SCL_10 41,42,54,55
BMC_I2C_SDA_10 41,42,54,55
I2C_IO_EXP_RESET# 44
HDD_LED_RESET_N 23
BUS_SW_EN23
P3V3_STBY_PG57,58
SAS_FAULT_LED10 38
SAS_FAULT_LED13 38
SAS_FAULT_LED12 38
SAS_FAULT_LED11 38
SAS_FAULT_LED15 38
SAS_FAULT_LED14 38
SAS_FAULT_LED9 38
SAS_FAULT_LED8 38
SAS_FAULT_LED7 38
SAS_FAULT_LED1 38
SAS_FAULT_LED6 38
SAS_FAULT_LED5 38
SAS_FAULT_LED4 38
SAS_FAULT_LED3 38
SAS_FAULT_LED2 38
SAS_FAULT_LED0 38
SAS_FAULT_LED7 38
SAS_FAULT_LED8 38
SAS_FAULT_LED9 38
SAS_FAULT_LED5 38
SAS_FAULT_LED6 38
SAS_FAULT_LED1 38
SAS_FAULT_LED2 38
SAS_FAULT_LED3 38
SAS_FAULT_LED4 38
SAS_FAULT_LED0 38
SAS_FAULT_LED10 38
SAS_FAULT_LED11 38
SAS_FAULT_LED12 38
SAS_FAULT_LED13 38
SAS_FAULT_LED14 38
SAS_FAULT_LED15 38
EXP_SCL_L_0 30
EXP_SDA_L_0 30
Title 
Size Document Number Re v 
Date: Sheet o f 
Honey badger_LSI Base Board 1B
HDD POWER & FAULT_LED
Custom
37 71Tuesday, January 20, 2015
Honey badger_LSI Base Board
http://www.wiwynn.com
8F, 90, Sec.1, Xintai 5th Rd., Xizhi Dist.,
New Taipei City 22102, Taiwan (R.O.C.)
Title 
Size Document Number Re v 
Date: Sheet o f 
Honey badger_LSI Base Board 1B
HDD POWER & FAULT_LED
Custom
37 71Tuesday, January 20, 2015
Honey badger_LSI Base Board
http://www.wiwynn.com
8F, 90, Sec.1, Xintai 5th Rd., Xizhi Dist.,
New Taipei City 22102, Taiwan (R.O.C.)
Title 
Size Document Number Re v 
Date: Sheet o f 
Honey badger_LSI Base Board 1B
HDD POWER & FAULT_LED
Custom
37 71Tuesday, January 20, 2015
Honey badger_LSI Base Board
http://www.wiwynn.com
8F, 90, Sec.1, Xintai 5th Rd., Xizhi Dist.,
New Taipei City 22102, Taiwan (R.O.C.)
SC428
SCD1U16V2KX-3GP
1 2
SC432
SC1U10V3KX-4GP-U
12
R5070R2J-2-GP NOPOP12
SR299 0R2J-2-GPNOPOP1 2
R6600R2J-2-GP NOPOP12
SC431
SCD1U16V2KX-3GP
1 2
R5110R2J-2-GP NOPOP12
SR950 
4K7R2F-GP 
NOPOP 12
R5080R2J-2-GP NOPOP12
R5600R2J-2-GP NOPOP12
R6280R2J-2-GP NOPOP12
R630 
4K7R2F-GP 
1 2
SR312 0R2J-2-GPNOPOP1 2
SU15
PI3C3861-AQE-GP
NC#11
A02
A13
A24
A35
A46
A57
A68
A79
A810
A911
GND 12
B9 13B8 14B7 15B6 16B5 17B4 18B3 19B2 20B1 21B0 22
BE# 23VCC24
SR947 
4K7R2F-GP 
NOPOP 12
SR783 
4K7R2F-GP 
12
SR949 
4K7R2F-GP 
NOPOP 12
SR316 0R2J-2-GPNOPOP1 2
SR955 
4K7R2F-GP 
NOPOP 12
SR844 
4K7R2F-GP 
NOPOP 12
R6660R2J-2-GP NOPOP12
R644 
4K7R2F-GP 
NOPOP 
1 2
SU16
PI3C3861-AQE-GP
NC#11
A02
A13
A24
A35
A46
A57
A68
A79
A810
A911
GND 12
B9 13B8 14B7 15B6 16B5 17B4 18B3 19B2 20B1 21B0 22
BE# 23VCC24
R654 
4K7R2F-GP 
NOPOP 
1 2
SR297 0R2J-2-GP1 2
R6610R2J-2-GP NOPOP12
SR954 
4K7R2F-GP 
NOPOP 12
SR310 0R2J-2-GP1 2
R632 
4K7R2F-GP 
NOPOP 
1 2
SC860 
SCD1U16V2KX-3GP 
1 2
SR590 
4K7R2F-GP 
12
SR839 
4K7R2F-GP 
12
R5140R2J-2-GP NOPOP12
R6650R2J-2-GP NOPOP12
R635 
4K7R2F-GP 
NOPOP 
1 2
SR842 
200KR2F-L-GP 
12
R649 
4K7R2F-GP 
1 2
R5020R2J-2-GP NOPOP12
SR309 0R2J-2-GP1 2
R618 0R2J-2-GP1 2
SC1286 
SCD1U16V2KX-3GP 
1 2 R5160R2J-2-GP NOPOP12
R5040R2J-2-GP NOPOP12
R617 0R2J-2-GPNOPOP1 2
SR265
0R2J-2-GP
1 2
U50
SN74LVC1G08DCKR-GP
B2
A1
GND3 Y 4
VCC 5
SU14
PCA9575PW2-GP
P1_0 26
P1_1 25
P1_2 24
P1_3 23
P1_4 20
P1_5 19
VSS 16P1_7 17P1_6 18
VDD2
VDD(IO)09
INT#14
RESET#3
A01
A18
A2 15
P0_04
P0_15
P0_26
P0_37
P0_410
P0_511
P0_612
P0_713
VDD(IO)1 21A3 22
SCL 28
SDA 27
R653 
4K7R2F-GP 
NOPOP 
1 2
SU52
PCA9306DCTT-GP
GND1
VREF12
SCL13
SDA14 SDA2 5
SCL2 6
VREF2 7
EN 8
R624
10KR2F-2-GP
12
SR314 0R2J-2-GPNOPOP1 2
R634 
4K7R2F-GP 
NOPOP 
1 2
R6620R2J-2-GP NOPOP12
SR845 
4K7R2F-GP 
NOPOP 12
SC546
SCD1U16V2KX-3GP
1 2
R636 
4K7R2F-GP 
1 2
R6290R2J-2-GP NOPOP12
SR956 
4K7R2F-GP 
NOPOP 12
SR262
0R2J-2-GP
1 2
R622
10KR2F-2-GP
12
R6690R2J-2-GP NOPOP12
SR311 0R2J-2-GP1 2
SC564 
SCD1U16V2KX-3GP 
1 2
SC429
SCD1U16V2KX-3GP
1 2
SR2634K7R2F-GP1 2
SR580 
200KR2F-L-GP 
12
SU17
PCA9575PW2-GP
NOPOP
P1_0 26
P1_1 25
P1_2 24
P1_3 23
P1_4 20
P1_5 19
VSS 16P1_7 17P1_6 18
VDD2
VDD(IO)09
INT#14
RESET#3
A01
A18
A2 15
P0_04
P0_15
P0_26
P0_37
P0_410
P0_511
P0_612
P0_713
VDD(IO)1 21A3 22
SCL 28
SDA 27
U188
PCA9552PW-GP
A01
A12
A23
LED04
LED15
LED26
LED37
LED48
LED59
LED610
LED711 VSS 12
LED8 13
LED9 14
LED10 15
LED11 16
LED12 17
LED13 18
LED14 19
LED15 20
RESET# 21
SCL 22
SDA 23
VDD24
SC434
SC1U10V3KX-4GP-U
12
SC1285 
SCD1U16V2KX-3GP 
1 2
SR579 
4K7R2F-GP 
12
R6190R2J-2-GP NOPOP12
Q92
2N7002A-7-GP
G
SD
R5030R2J-2-GP NOPOP12
R5950R2J-2-GP NOPOP12
SC867 
SCD1U16V2KX-3GP 
1 2
SR307 0R2J-2-GPNOPOP1 2
R642 
4K7R2F-GP 
1 2
SR269
4K7R2F-GP1 2
SR298 0R2J-2-GP1 2
R5170R2J-2-GP NOPOP12
SR305 0R2J-2-GPNOPOP1 2
R645 
4K7R2F-GP 
1 2
R623
10KR2F-2-GP
NOPOP
1 2
SC427
SCD1U16V2KX-3GP
1 2
SR271
4K7R2F-GP
1 2
SR846 
4K7R2F-GP 
NOPOP 12
SC435
SCD1U16V2KX-3GP
1 2
SR270
4K7R2F-GP
1 2
R648 
4K7R2F-GP 
1 2
R641 
4K7R2F-GP 
1 2
R5090R2J-2-GP NOPOP12
R643 
4K7R2F-GP 
NOPOP 
1 2
SR945 
4K7R2F-GP 
NOPOP 12
R652 
4K7R2F-GP 
1 2
SU18
PI3C3861-AQE-GP
NC#11
A02
A13
A24
A35
A46
A57
A68
A79
A810
A911
GND 12
B9 13B8 14B7 15B6 16B5 17B4 18B3 19B2 20B1 21B0 22
BE# 23VCC24
R5060R2J-2-GP NOPOP12
R5150R2J-2-GP NOPOP12
R5100R2J-2-GP NOPOP12
R5120R2J-2-GP NOPOP12
SR315 0R2J-2-GPNOPOP1 2
R650 
4K7R2F-GP 
NOPOP 
1 2
SC547
SCD1U16V2KX-3GP
1 2
R621 0R2J-2-GP
NOPOP
1 2
SR952 
4K7R2F-GP 
NOPOP 12
SR304 0R2J-2-GPNOPOP1 2
R639 
4K7R2F-GP 
1 2
SC545
SCD1U16V2KX-3GP
1 2
SR953 
4K7R2F-GP 
NOPOP 12
R637 
4K7R2F-GP 
1 2
R640 
4K7R2F-GP 
NOPOP 
1 2
R6640R2J-2-GP NOPOP12
R5050R2J-2-GP NOPOP12
SR313 0R2J-2-GPNOPOP1 2
SR589 
4K7R2F-GP 
12
SR946 
4K7R2F-GP 
NOPOP 12
SR951 
4K7R2F-GP 
NOPOP 12
SR266
4K7R2F-GP
12
R6680R2J-2-GP NOPOP12
SR948 
4K7R2F-GP 
NOPOP 12
SC436
SCD1U16V2KX-3GP
1 2
R6670R2J-2-GP NOPOP12
R5130R2J-2-GP NOPOP12
SU74
PCA9306DCTT-GP
GND1
VREF12
SCL13
SDA14 SDA2 5
SCL2 6
VREF2 7
EN 8
SR843 
4K7R2F-GP 
NOPOP 12
SR578 
4K7R2F-GP 
12
SC433
SCD1U16V2KX-3GP
1 2
R633 
4K7R2F-GP 
1 2
R625
0R2J-2-GP1 2
SR296 0R2J-2-GPNOPOP1 2
R6630R2J-2-GP NOPOP12
SU13
PI3C3861-AQE-GP
NC#11
A02
A13
A24
A35
A46
A57
A68
A79
A810
A911
GND 12
B9 13B8 14B7 15B6 16B5 17B4 18B3 19B2 20B1 21B0 22
BE# 23VCC24
SC430
SC1U10V3KX-4GP-U
12
SR306 0R2J-2-GPNOPOP1 2
SC634 
SCD1U16V2KX-3GP 
1 2
R5940R2J-2-GP NOPOP12
SR308 0R2J-2-GPNOPOP1 2
SC426
SC1U10V3KX-4GP-U
12
R651 
4K7R2F-GP 
NOPOP 
1 2
R631 
4K7R2F-GP 
NOPOP 
1 2



5
5
4
4
3
3
2
2
1
1
D D
C C
B B
A A
1: not mated 
0. Mated 
x16 PCIe 164 PINs GOLDEN FINGER 
         STRADDLE TYPE 
x1 PCIe 36 PINs GOLDEN FINGER 
         STRADDLE TYPE 
SELF_TRAY
TRAY_ID
SAS_I2C_B_BUF_SDA_R
PEER_1B_2B_HB
PEER_TRAY
SAS_I2C_B_BUF_SDA_R
SAS_I2C_B_BUF_SCL_R
SAS_I2C_D_BUF_SCL_R
HB_INPUT
SAS_I2C_C_BUF_SCL_R
SAS_I2C_C_BUF_SDA_R
SAS_I2C_D_BUF_SDA_R ID_I2C_ADD
SAS_I2C_B_BUF_SCL_RSAS_I2C_C_BUF_SDA_R
SAS_I2C_C_BUF_SCL_R
SAS_SEB_PEER_PRSNT
PCIe_MATED#_A
PCIe_MATED#_B
P12V_PCIE
P12V_PCIE
P3V3_STBY
P12V_PCIE
P12V_PCIE
P12V_PCIE
P12V_PCIE
SAS_FAULT_LED137
SAS_FAULT_LED037
SAS_HDD_PRE15 23,37
HB_OUT 31,32
HB_B_SIDE_IN 44
SAS_FAULT_LED9 37
SAS_HDD_PWR1_PCIe 37
SAS_HDD_PWR2_PCIe 37
SAS_HDD_PWR3_PCIe 37
SAS_HDD_PWR4_PCIe 37
SAS_HDD_PWR5_PCIe 37
SAS_HDD_PWR6_PCIe 37
SAS_HDD_PWR7_PCIe 37
SAS_HDD_PWR8_PCIe 37
SAS_HDD_PWR9_PCIe 37
SAS_HDD_PWR0_PCIe 37
SAS_HDD_PWR10_PCIe 37
SAS_HDD_PRE923,37
SAS_HDD_PRE823,37
SAS_HDD_PRE723,37
SAS_HDD_PRE623,37
SAS_HDD_PRE523,37
SAS_HDD_PRE423,37
SAS_HDD_PRE323,37
SAS_HDD_PRE223,37
SAS_HDD_PRE123,37
SAS_HDD_PRE023,37
SAS_HDD_PRE1423,37
SAS_HDD_PRE1323,37
SAS_HDD_PRE1223,37
SAS_HDD_PRE1123,37
SAS_HDD_PRE1023,37
SAS_HDD_PWR15_PCIe 37
SAS_HDD_PWR11_PCIe 37
SAS_HDD_PWR12_PCIe 37
SAS_HDD_PWR13_PCIe 37
SAS_HDD_PWR14_PCIe 37
BMC_SELF_TRAY44
PEER_TRAY_R23,44
FAN_PWM_PCIe 23,44
FCB_HW_REVISION 23,44
DPB_HW_REVISION 23,44
EXP_TRAY_ID23,44
PEER_1B_2B_HB23,44
PEER_1A_2A_HB 23,44
SAS_SEB_PEER_PRSNT_BMC44
SAS_FAULT_LED237
SAS_FAULT_LED337
SAS_FAULT_LED437
SAS_FAULT_LED537
SAS_FAULT_LED637
SAS_FAULT_LED737
SAS_FAULT_LED837
SAS_FAULT_LED10 37
SAS_FAULT_LED11 37
SAS_FAULT_LED12 37
SAS_FAULT_LED13 37
SAS_FAULT_LED14 37
SAS_FAULT_LED15 37
EXP_ID 44
SAS_I2C_B_BUF_SCL 51
SAS_I2C_C_BUF_SCL 51
SAS_I2C_B_BUF_SDA 51
SAS_I2C_C_BUF_SDA 51
SAS_GF_EXP_RX_DP022
SAS_GF_EXP_RX_DN022
SAS_GF_EXP_RX_DP222
SAS_GF_EXP_RX_DN222
SAS_GF_EXP_RX_DN122
SAS_GF_EXP_RX_DP122
SAS_GF_EXP_RX_DN322
SAS_GF_EXP_RX_DP322
SAS_GF_EXP_RX_DP1121
SAS_GF_EXP_RX_DN1121
SAS_GF_EXP_RX_DP1221
SAS_GF_EXP_RX_DN1221
SAS_GF_EXP_RX_DN1321
SAS_GF_EXP_RX_DP1321
SAS_GF_EXP_RX_DN1421
SAS_GF_EXP_RX_DP1421
SAS_GF_EXP_RX_DP421
SAS_GF_EXP_RX_DN421
SAS_GF_EXP_RX_DP1021
SAS_GF_EXP_RX_DN1021
SAS_GF_EXP_RX_DN921
SAS_GF_EXP_RX_DP921
SAS_GF_EXP_RX_DP830
SAS_GF_EXP_RX_DN830
SAS_GF_EXP_RX_DN730
SAS_GF_EXP_RX_DP730
SAS_GF_EXP_RX_DN621
SAS_GF_EXP_RX_DP621
SAS_GF_EXP_RX_DN521
SAS_GF_EXP_RX_DP521
SAS_GF_EXP_RX_DP1521
SAS_GF_EXP_RX_DN1521
SAS_EXP_GF_TX_DP0 22
SAS_EXP_GF_TX_DN0 22
SAS_EXP_GF_TX_DP1 22
SAS_EXP_GF_TX_DN1 22
SAS_EXP_GF_TX_DP2 22
SAS_EXP_GF_TX_DN2 22
SAS_EXP_GF_TX_DP3 22
SAS_EXP_GF_TX_DN3 22
SAS_EXP_GF_TX_DN4 21
SAS_EXP_GF_TX_DP4 21
SAS_EXP_GF_TX_DN5 21
SAS_EXP_GF_TX_DP5 21
SAS_EXP_GF_TX_DN6 21
SAS_EXP_GF_TX_DP6 21
SAS_HDD_CONN_TX7_P 30
SAS_HDD_CONN_TX7_N 30
SAS_HDD_CONN_TX8_P 30
SAS_HDD_CONN_TX8_N 30
SAS_EXP_GF_TX_DP9 21
SAS_EXP_GF_TX_DN9 21
SAS_EXP_GF_TX_DN10 21
SAS_EXP_GF_TX_DP10 21
SAS_EXP_GF_TX_DP11 21
SAS_EXP_GF_TX_DN11 21
SAS_EXP_GF_TX_DN12 21
SAS_EXP_GF_TX_DP12 21
SAS_EXP_GF_TX_DP13 21
SAS_EXP_GF_TX_DN13 21
SAS_EXP_GF_TX_DP14 21
SAS_EXP_GF_TX_DN14 21
SAS_EXP_GF_TX_DN15 21
SAS_EXP_GF_TX_DP15 21
PCIe_MATED#_A 55
SHUTDOWN_RELEASE53
EXP_SELF_TRAY23
PCIe_MATED#_B55
Title 
Size Document Number Rev 
Date: Sheet o f 
Honey badger_LSI Base Board 1B
SAS PCI-E GOLD FINGER
A2
38 71Tuesday, January 20, 2015
Honey badger_LSI Base Board
http://www.wiwynn.com
8F, 90, Sec.1, Xintai 5th Rd., Xizhi Dist.,
New Taipei City 22102, Taiwan (R.O.C.)
Title 
Size Document Number Rev 
Date: Sheet o f 
Honey badger_LSI Base Board 1B
SAS PCI-E GOLD FINGER
A2
38 71Tuesday, January 20, 2015
Honey badger_LSI Base Board
http://www.wiwynn.com
8F, 90, Sec.1, Xintai 5th Rd., Xizhi Dist.,
New Taipei City 22102, Taiwan (R.O.C.)
Title 
Size Document Number Rev 
Date: Sheet o f 
Honey badger_LSI Base Board 1B
SAS PCI-E GOLD FINGER
A2
38 71Tuesday, January 20, 2015
Honey badger_LSI Base Board
http://www.wiwynn.com
8F, 90, Sec.1, Xintai 5th Rd., Xizhi Dist.,
New Taipei City 22102, Taiwan (R.O.C.)
R158
0R2J-2-GP
1 2
Top Bottom 
02 Do not mirror 
GF7
GF-PCIE-36P-GP
B1 B1
B2 B2
B3 B3
B4 B4
B5 B5
B6 B6
B7 B7
B8 B8
B9 B9
B10 B10
B11 B11
B12 B12
B13 B13
B14 B14
B15 B15
B16 B16
B17 B17
B18 B18
A1A1
A2A2
A3A3
A4A4
A5A5
A6A6
A7A7
A8A8
A9A9
A10A10
A11A11
A12A12
A13A13
A14A14
A15A15
A16A16
A17A17
A18A18
R150 0R2J-2-GP1 2
R627
10KR2F-2-GP
1 2
R626
27KR2F-L-GP
1 2
R156
0R2J-2-GP
1 2
Top Bottom 
02 Do not mirror 
GF6
GF-PCIE-36P-GP
B1 B1
B2 B2
B3 B3
B4 B4
B5 B5
B6 B6
B7 B7
B8 B8
B9 B9
B10 B10
B11 B11
B12 B12
B13 B13
B14 B14
B15 B15
B16 B16
B17 B17
B18 B18
A1A1
A2A2
A3A3
A4A4
A5A5
A6A6
A7A7
A8A8
A9A9
A10A10
A11A11
A12A12
A13A13
A14A14
A15A15
A16A16
A17A17
A18A18
R518
27KR2F-L-GP
1 2
TP78
1
C299 
SC1U25V3KX-GP 
1 2
R155
0R2J-2-GP
1 2
TP79
1
R257
10KR2F-2-GP
1 2
C300
SC22U25V5MX-GP 
1 2
R151 0R2J-2-GP1 2
C298 
SCD1U25V2KX-2-GP 
1 2
C297 
SCD1U25V2KX-2-GP 
1 2
TOP BOTTOM 
GF1
GF-X16-U
B1 B1
B2 B2
B3 B3
B4 B4
B5 B5
B6 B6
B7 B7
B8 B8
B9 B9
B10 B10
B11 B11
B12 B12
B13 B13
B14 B14
B15 B15
B16 B16
B17 B17
B18 B18
B19 B19
B20 B20
B21 B21
B22 B22
B23 B23
B24 B24
B25 B25
B26 B26
B27 B27
B28 B28
B29 B29
B30 B30
B31 B31
B32 B32
B33 B33
B34 B34
B35 B35
B36 B36
B37 B37
B38 B38
B39 B39
B40 B40
B41 B41
B42 B42
B43 B43
B44 B44
B45 B45
B46 B46
B47 B47
B48 B48
B49 B49
B50 B50
B51 B51
B52 B52
B53 B53
B54 B54
B55 B55
B56 B56
B57 B57
B58 B58
B59 B59
B60 B60
B61 B61
B62 B62
B63 B63
B64 B64
B65 B65
B66 B66
B67 B67
B68 B68
B69 B69
B70 B70
B71 B71
B72 B72
B73 B73
B74 B74
B75 B75
B76 B76
B77 B77
B78 B78
B79 B79
B80 B80
B81 B81
B82 B82
A1A1
A2A2
A3A3
A4A4
A5A5
A6A6
A7A7
A8A8
A9A9
A10A10
A11A11
A12A12
A13A13
A14A14
A15A15
A16A16
A17A17
A18A18
A19A19
A20A20
A21A21
A22A22
A23A23
A24A24
A25A25
A26A26
A27A27
A28A28
A29A29
A30A30
A31A31
A32A32
A33A33
A34A34
A35A35
A36A36
A37A37
A38A38
A39A39
A40A40
A41A41
A42A42
A43A43
A44A44
A45A45
A46A46
A47A47
A48A48
A49A49
A50A50
A51A51
A52A52
A53A53
A54A54
A55A55
A56A56
A57A57
A58A58
A59A59
A60A60
A61A61
A62A62
A63A63
A64A64
A65A65
A66A66
A67A67
A68A68
A69A69
A70A70
A71A71
A72A72
A73A73
A74A74
A75A75
A76A76
A77A77
A78A78
A79A79
A80A80
A81A81
A82A82
R152 0R2J-2-GP1 2
R149 0R2J-2-GP1 2
C296
SC22U25V5MX-GP 
1 2
R1480R2J-2-GP 12
C302 
SC1U25V3KX-GP 
1 2
R153 0R2J-2-GP1 2
C303 
SCD1U25V2KX-2-GP 
1 2
C301 
SCD1U25V2KX-2-GP 
1 2
R154 0R2J-2-GP1 2
R519
10KR2F-2-GP
1 2
R157
0R2J-2-GP
1 2



5
5
4
4
3
3
2
2
1
1
D D
C C
B B
A A
ADD=10100010 (0xA2) 
RTC 
P3V0_BAT_R
P3V3_RTC
RTC_I2C_SCL
RTC_I2C_SDA
RTC_CLK_OUT
RTC_OSCI
RTC_OSCO
RTC_INT_N
P3V0_BAT
P3V3_STBY
P3V3_RTC
BMC_I2C_A_SDA 41,42,54,55
BMC_I2C_A_SCL 41,42,54,55
Title 
Size Document Number R e v 
Date: Sheet 
o f 
Honey badger_LSI Base Board 1B
RTC
A3
39 71Tuesday, January 20, 2015
Honey badger_LSI Base Board
http://www.wiwynn.com
8F, 90, Sec.1, Xintai 5th Rd., Xizhi Dist.,
New Taipei City 22102, Taiwan (R.O.C.)
Title 
Size Document Number R e v 
Date: Sheet 
o f 
Honey badger_LSI Base Board 1B
RTC
A3
39 71Tuesday, January 20, 2015
Honey badger_LSI Base Board
http://www.wiwynn.com
8F, 90, Sec.1, Xintai 5th Rd., Xizhi Dist.,
New Taipei City 22102, Taiwan (R.O.C.)
Title 
Size Document Number R e v 
Date: Sheet 
o f 
Honey badger_LSI Base Board 1B
RTC
A3
39 71Tuesday, January 20, 2015
Honey badger_LSI Base Board
http://www.wiwynn.com
8F, 90, Sec.1, Xintai 5th Rd., Xizhi Dist.,
New Taipei City 22102, Taiwan (R.O.C.)
R5202
1KR2J-1-GP
1 2
R5201 0R2J-2-GP1 2
U43
PCF8563T-1-GP
OSCI1
OSCO2
INT#3
VSS4 SDA 5SCL 6CLKOUT 7VDD 8
TP8001
R655 
4K7R2F-GP 
1 2
C307
SC15P50V2JN-2-GP
NOPOP
1 2
BAT1
BAT-AAA-BAT-043-K01-GP
1 2
3
C1698
SC22U6D3V5MX-2GP
1 2
D13
BAT54C-7-F-3-GP
1
2
3
R1848
10MR3F-GP
NOPOP
1 2
X2
X-32D768KHZ-56GP
1 2
C306
SC15P50V2JN-2-GP
NOPOP
1 2
R5200 0R2J-2-GP1 2



5
5
4
4
3
3
2
2
1
1
D D
C C
B B
A A
PCIE_10G_CPU_RX3_N
PCIE_10G_CPU_RX3_P
SMB_LAN_ALERT_N
CLK_100M_CLKBUFF_ENET2_DN
PMU_PLTRST_N_10G
NCSI_10G_RXD1_R
NCSI_10G_RXD0_R
PCIE_10G_CPU_RX0_N
PCIE_10G_CPU_RX0_P
SAS_I2C_C_10G_SDA
SAS_I2C_C_10G_SCL
PMU_WAKE_N_R
PCIE_10G_REFCLK_2_P
NCSI_10G_TXD1_R
NCSI_10G_TXD0_R
PCIE_10G_CPU_RX1_N
PCIE_10G_CPU_RX1_P
PCIE_10G_REFCLK_P
PCIE_10G_REFCLK_N
NCSI_10G_RCSDV_R
NCSI_10G_RCLK_R
NCSI_10G_TXEN_R
PCIE_10G_CPU_TX0_N
PCIE_10G_CPU_TX1_P
PCIE_10G_CPU_TX1_N
PCIE_10G_CPU_TX3_N
PCIE_10G_CPU_TX3_P
PCIE_10G_CPU_TX2_N
PCIE_10G_CPU_TX2_P
PCIE_10G_REFCLK_2_N
PCIE_10G_CPU_TX0_P
PCIE_10G_CPU_RX2_N
PCIE_10G_CPU_RX2_P
NCSI_10G_RX_ER_R
CLK_100M_CLKBUFF_ENET2_DP
I2C_BMC_MSB_CLK_R
I2C_BMC_MSB_DATA_R
P5V_STBY
P12V
P3V3
P3V3_STBY
P3V3_STBY
P3V3
P3V3_STBY
P12V
P5V_STBY
P3V3_STBY
P3V3
PCIE_10G_CPU_RX0_N 33
PCIE_10G_CPU_RX0_P 33
PCIE_10G_CPU_RX2_N 33
PCIE_10G_CPU_RX1_N 33
PCIE_10G_CPU_RX1_P 33
PCIE_10G_CPU_RX2_P 33
PCIE_10G_CPU_RX3_N 33
PCIE_10G_CPU_RX3_P 33
CONN_10G_PRSNT2_N44
PMU_WAKE_N43
CLK_100M_CLKBUFF_ENET2_DP 33
CLK_100M_CLKBUFF_ENET2_DN 33
PCIE_10G_CPU_TX0_P33
PCIE_10G_CPU_TX0_N33
PCIE_10G_CPU_TX1_P33
PCIE_10G_CPU_TX1_N33
PCIE_10G_CPU_TX2_P33
PCIE_10G_CPU_TX2_N33
PCIE_10G_CPU_TX3_P33
PCIE_10G_CPU_TX3_N33
I2C_BMC_10G_ALERT#42
BMC_10G_SDA_242
BMC_10G_SCL_242
NCSI_10G_TXD143
NCSI_10G_TXD043
NCSI_10G_RX_ER43
CLK_100M_CLKBUFF_ENET1_DN33
CLK_100M_CLKBUFF_ENET1_DP33
NCSI_10G_RCLK 48
NCSI_10G_RCSDV 43
NCSI_10G_TXEN 43
NCSI_10G_RXD0 43
NCSI_10G_RXD1 43
BMC_MBC_I2C_E_SDA 33,42
BMC_MBC_I2C_E_SCL 33,42
CONN_10G_PRSNT2_N 44
PMU_PLTRST_N 13,18,31,33,42,44,50,52
Title 
Size Document Number Rev 
Date: Sheet o f 
Honey badger_LSI Base Board 1B
10G MEZZ CARD
Custom
40 71Tuesday, January 20, 2015
Honey badger_LSI Base Board
http://www.wiwynn.com
8F, 90, Sec.1, Xintai 5th Rd., Xizhi Dist.,
New Taipei City 22102, Taiwan (R.O.C.)
Title 
Size Document Number Rev 
Date: Sheet o f 
Honey badger_LSI Base Board 1B
10G MEZZ CARD
Custom
40 71Tuesday, January 20, 2015
Honey badger_LSI Base Board
http://www.wiwynn.com
8F, 90, Sec.1, Xintai 5th Rd., Xizhi Dist.,
New Taipei City 22102, Taiwan (R.O.C.)
Title 
Size Document Number Rev 
Date: Sheet o f 
Honey badger_LSI Base Board 1B
10G MEZZ CARD
Custom
40 71Tuesday, January 20, 2015
Honey badger_LSI Base Board
http://www.wiwynn.com
8F, 90, Sec.1, Xintai 5th Rd., Xizhi Dist.,
New Taipei City 22102, Taiwan (R.O.C.)
C282 
SCD1U25V2KX-2-GP 
1 2
R205 0R2J-2-GP 12
R214 0R2J-2-GP1 2
R206 0R2J-2-GP 12
R254 0R2J-2-GPNOPOP 12
R218 0R2J-2-GP 12
R220 0R2J-2-GP 12
R255 0R2J-2-GPNOPOP 12
C285 
SCD1U25V2KX-2-GP 
1 2
R272 0R2J-2-GP 12
C276 
SC22U25V5MX-GP 
1 2
R211 0R2J-2-GP 12
R225 0R2J-2-GP1 2
C278 
SC1U25V3KX-GP 
1 2
R209 0R2J-2-GP 12
C279 
SCD1U25V2KX-2-GP 
1 2
MEZCN1
FCI-CONN120-GP
NP1
NP2
1
2
3
4
5
6
7
8
9
10
11
12
13
14
15
16
17
18
19
20
21
22
23
24
25
26
27
28
29
30
31
32
33
34
35
36
37
38
39
40
41
42
43
44
45
46
47
48
49
50
51
52
53
54
55
56
57
58
59
60
61
62
63
64
65
66
67
68
69
70
71
72
73
74
75
76
77
78
79
80
81
82
83
84
85
86
87
88
89
90
91
92
93
94
95
96
97
98
99
100
101
102
103
104
105
106
107
108
109
110
111
112
113
114
115
116
117
118
119
120
R224 0R2J-2-GP1 2
C277 
SCD1U25V2KX-2-GP 
1 2
R271 0R2J-2-GP 12
R226
10KR2F-2-GP
NOPOP
1 2
C286 
SCD1U25V2KX-2-GP 
1 2
R210 0R2J-2-GP 12
C281 
SC1U25V3KX-GP 
1 2
R273 0R2J-2-GP 12
C280 
SCD1U25V2KX-2-GP 
1 2
C283 
SCD1U25V2KX-2-GP 
1 2
C284 
SC1U25V3KX-GP 
1 2
R270 0R2J-2-GP 12
C287 
SC1U25V3KX-GP 
1 2
R213 0R2J-2-GP 12
R215 0R2J-2-GP 12
C288 
SCD1U25V2KX-2-GP 
1 2
R207 0R2J-2-GP 12



5
5
4
4
3
3
2
2
1
1
D D
C C
B B
A A
ADD=1010000 (0xA0) 
EEPROM 
ADD=10011000 (0x98) 
TEMP SENSOR 1 
ADD=1001001 (0x92) 
VOLTAGE SENSOR 1 
Internal POR 
ADD=1100000 (0xC0) 
LED DRIVER 
ADD=1001000 (0x90) 
VOLTAGE SENSOR 2 
ADD=1001010 (0x94) 
TEMP SENSOR 2 
ADD=1001011 (0x96) 
TEMP SENSOR 3 
ADD=1001101 (0x9A) 
TEMP SENSOR 4 
TEMP_1_A1
TEMP_SENSOR_DXN
TEMP_SENSOR_DXN_BJT
TEMP_SENSOR_DXP_R
TEMP_SENSOR_C
TEMP_SENSOR_DXP
TEMP_1_A0
5V_STBY_SENSE
VOL_SEN_ADDR
1V8_STBY_SENSE
VOL_SEN_ALERT
3V3_STBY_SENSE
EEPROM_A2_R
EEPROM_WP
EEPROM_A0_R
EEPROM_A1_R
LED_DR_RESET#
LED_DR_LED0
LED_DR_LED1
LED_DR_A0
LED_DR_I2C_SDA
LED_DR_I2C_SCL
TEMP_1_SCL
TEMP_1_SDA
VOL_SEN_SCL
VOL_SEN_SDA
EEPROM_SCL
EEPROM_SDA
VOL_SEN_SDA_U17
VOL_SEN_SCL_U17
P0V955_C_SENSE
P0V9_E_SENSE
P1V5_C_SENSE
VOL_SEN_ADDR_U17
VOL_SEN_ALERT_U17
P1V5_E_SENSE
Temp_2_A0
Temp_2_SCL
Temp_2_SDA
Temp_2_ALERT
Temp_2_A2
Temp_2_A1
Temp_3_A0
Temp_3_SCL
Temp_3_SDA
Temp_3_ALERT
Temp_3_A2
Temp_3_A1
Temp_4_A0
Temp_4_SCL
Temp_4_SDA
Temp_4_ALERT
Temp_4_A2
Temp_4_A1
12V_SENSE
P3V3_STBY
P3V3_STBY
P3V3_STBY
P3V3_STBY
P3V3_STBY
P3V3_STBY
P3V3_STBY
P3V3_STBY
P3V3_STBY
P3V3_STBY
P3V3_STBY
P3V3_STBY
P3V3_STBY
P3V3_STBY
P3V3_STBY
P3V3_STBY
P3V3_STBY
P3V3_STBY
LED_DR_LED0 44
BMC_I2C_A_SDA39,42,54,55
BMC_I2C_A_SCL39,42,54,55
BMC_I2C_SDA_1037,42,54,55
BMC_I2C_SCL_1037,42,54,55
BMC_I2C_SCL_10 37,42,54,55
BMC_I2C_SDA_10 37,42,54,55
BMC_I2C_A_SDA 39,42,54,55
BMC_I2C_A_SCL 39,42,54,55
BMC_I2C_A_SDA 39,42,54,55
BMC_I2C_A_SCL 39,42,54,55
BMC_I2C_SCL_10 37,42,54,55
BMC_I2C_SDA_10 37,42,54,55
BMC_I2C_D_SCL42,50
BMC_I2C_D_SDA42,50
BMC_I2C_SCL_1037,42,54,55
BMC_I2C_SDA_1037,42,54,55
LED_DR_LED1 31,44
BMC_I2C_A_SDA 39,42,54,55
BMC_I2C_SDA_10 37,42,54,55
BMC_I2C_SCL_10 37,42,54,55
BMC_I2C_A_SCL 39,42,54,55
BMC_I2C_SCL_1037,42,54,55
BMC_I2C_SDA_1037,42,54,55
BMC_I2C_D_SDA42,50
BMC_I2C_D_SCL42,50
BMC_I2C_D_SDA42,50
BMC_I2C_D_SCL42,50
BMC_I2C_SCL_1037,42,54,55
BMC_I2C_SDA_1037,42,54,55
BMC_I2C_D_SCL42,50
BMC_I2C_D_SDA42,50
BMC_I2C_SDA_1037,42,54,55
BMC_I2C_SCL_1037,42,54,55
ADC_12V44,47
ADC_P5V_STBY44,47
ADC_P3V3_STBY44,47
ADC_P1V8_STBY44,47
ADC_P0V9_E44,47
ADC_P0V955_C44,47
ADC_P1V5_E44,47
ADC_P1V5_C44,47
Title 
Size Document Number Rev 
Date: Sheet o f 
Honey badger_LSI Base Board 1B
AST1250 I2C DEVICE
A2
41 71Tuesday, January 20, 2015
Honey badger_LSI Base Board
http://www.wiwynn.com
8F, 90, Sec.1, Xintai 5th Rd., Xizhi Dist.,
New Taipei City 22102, Taiwan (R.O.C.)
Title 
Size Document Number Rev 
Date: Sheet o f 
Honey badger_LSI Base Board 1B
AST1250 I2C DEVICE
A2
41 71Tuesday, January 20, 2015
Honey badger_LSI Base Board
http://www.wiwynn.com
8F, 90, Sec.1, Xintai 5th Rd., Xizhi Dist.,
New Taipei City 22102, Taiwan (R.O.C.)
Title 
Size Document Number Rev 
Date: Sheet o f 
Honey badger_LSI Base Board 1B
AST1250 I2C DEVICE
A2
41 71Tuesday, January 20, 2015
Honey badger_LSI Base Board
http://www.wiwynn.com
8F, 90, Sec.1, Xintai 5th Rd., Xizhi Dist.,
New Taipei City 22102, Taiwan (R.O.C.)
U17
ADS1015IDGSR-GP
NOPOP
ADDR 1
ALERT/RDY 2
GND 3
AIN04
AIN15
AIN26
AIN37
VDD8
SDA 9SCL 10
TP168
TPAD32-GP
1
R587
0R2J-2-GP
1 2
R185
4K7R2F-GP
NOPOP
1 2
R611 
4K7R2F-GP 
1 2
R53010R2J-2-GP NOPOP1 2
R585 
4K7R2F-GP 
NOPOP 
1 2
R589 
4K7R2F-GP 
NOPOP 
1 2R195 
4K7R2F-GP 
1 2
TP83
TPAD32-GP
1
U16
24LC64-I-SN-GP
A01
A12
A23
VSS4 SDA 5SCL 6WP 7VCC 8
C326 
SCD1U16V2KX-3GP 
1 2
R1910R2J-2-GP1 2
R164 
4K7R2F-GP 
NOPOP 
1 2
R572 0R2J-2-GP1 2
R177 
4K7R2F-GP 
1 2
C327 
SCD1U16V2KX-3GP 
1 2
R53130R2J-2-GP NOPOP1 2
R169 0R2J-2-GP1 2
TP84
TPAD32-GP
1
R184 0R2J-2-GP1 2
R564 0R2J-2-GP1 2
TP171
TPAD32-GP
1
C146
SCD1U16V2KX-3GP
1 2
R570 0R2J-2-GP1 2
R5304 0R2J-2-GPNOPOP1 2
R160 
4K7R2F-GP 
1 2
R1900R2J-2-GP1 2
R193
8K2R2J-3-GP
NOPOP
1 2
R176 
4K7R2F-GP 
NOPOP 
1 2
R189 
4K7R2F-GP 
NOPOP 
1 2
R186
4K7R2F-GP
1 2
C145
SC1U10V2KX-4-GP
1 2
R5305 0R2J-2-GPNOPOP1 2
R159
0R2J-2-GP
1 2
R568 0R2J-2-GP1 2
R53150R2J-2-GP NOPOP1 2
R567
4K7R2F-GP
NOPOP
1 2
R53090R2J-2-GP NOPOP1 2
R192
8K2R2J-3-GP
NOPOP
1 2
R597 
4K7R2F-GP 
NOPOP 
1 2
R5311 0R2J-2-GPNOPOP1 2
R591 
4K7R2F-GP 
NOPOP 
1 2
C153
SC100P50V2JN-3GP
NOPOP
1 2
R590 
4K7R2F-GP 
1 2
R592 
4K7R2F-GP 
1 2
R167 
4K7R2F-GP 
1 2
C323
SCD1U16V2KX-3GP
1 2
R201 49D9R2D-GP1 2
R161 
4K7R2F-GP 
1 2
R53120R2J-2-GP NOPOP1 2
R170 
100KR2F-L1-GP 
1 2
R179 0R2J-2-GP1 2
U136
TMP75AIDGKR-GP
SDA1
SCL2
ALERT3
GND4 A2 5A1 6A0 7V+ 8
C320
SC1U10V2KX-4-GP
1 2
R178 
4K7R2F-GP 
1 2
R162
0R2J-2-GP
1 2
C151 
SCD1U16V2KX-3GP 
1 2
R53140R2J-2-GP NOPOP1 2
R198
8K2R2J-3-GP
1 2
R180 0R2J-2-GP1 2
R53020R2J-2-GP NOPOP1 2
R202 49D9R2D-GP
1 2
R165 
4K7R2F-GP 
NOPOP 
1 2
C143 
SCD01U50V2KX-1GP 
1 2
R586 
4K7R2F-GP 
NOPOP 
1 2
Q4
MPS2907ARLRAG-GP
C
B
E
R53080R2J-2-GP NOPOP1 2
R53060R2J-2-GP NOPOP1 2
R187
4K7R2F-GP
NOPOP
1 2
R5310 0R2J-2-GPNOPOP1 2
R53000R2J-2-GP NOPOP1 2
R53030R2J-2-GP NOPOP1 2
R163
4K7R2F-GP
1 2
U12
PCA9550DP-1-GP
A01
LED0 2
LED1 3
VSS 4
RESET#5
SCL6
SDA7
VDD 8
R188 
4K7R2F-GP 
NOPOP 
1 2
R588
0R2J-2-GP
1 2
R203
0R2J-2-GP
NOPOP
12
R168 0R2J-2-GP1 2
R208 0R2J-2-GP1 2
R200
8K2R2J-3-GP
1 2
R571
4K7R2F-GP
1 2
U14
ADS1015IDGSR-GP
NOPOP
ADDR 1
ALERT/RDY 2
GND 3
AIN04
AIN15
AIN26
AIN37
VDD8
SDA 9SCL 10
R199
8K2R2J-3-GP
1 2
R196 
4K7R2F-GP 
1 2
TP170
TPAD32-GP
1
R182 0R2J-2-GP1 2
R204 0R2J-2-GP
1 2
U134
TMP75AIDGKR-GP
SDA1
SCL2
ALERT3
GND4 A2 5A1 6A0 7V+ 8
R171 
100KR2F-L1-GP 
1 2
R172
4K7R2J-2-GP
1 2
C152
SCD1U16V2JX-1-GP
1 2
R566 0R2J-2-GP1 2
R53070R2J-2-GP NOPOP1 2
R194
8K2R2J-3-GP
NOPOP
1 2
TP166
TPAD32-GP
1
R197
8K2R2J-3-GP
1 2
R183 0R2J-2-GP1 2
R565 0R2J-2-GP1 2
U15
TMP421AIDCNRG4-GP
DXP 1
DXN 2
A1 3
A0 4GND5 SDA6 SCL7 V+8
C328 
SCD1U16V2KX-3GP 
1 2
R569
4K7R2F-GP
NOPOP
1 2
R596
0R2J-2-GP
1 2
R212 0R2J-2-GP1 2
R166 
4K7R2F-GP 
1 2
R175 
4K7R2F-GP 
NOPOP 
1 2
R593
0R2J-2-GP
1 2
C142 
SCD1U16V2KX-3GP 
1 2
U135
TMP75AIDGKR-GP
SDA1
SCL2
ALERT3
GND4 A2 5A1 6A0 7V+ 8
R181 0R2J-2-GP1 2



5
5
4
4
3
3
2
2
1
1
D D
C C
B B
A A
DDR3 Vref 
BMC_SALT3
I2C_BMC_10G_ALERT#
BMC_MSB_I2C_E_ALERT_#
BMC_I2C_D_SDA
BMC_I2C_D_SCL
BMC0_SMB6_DAT
BMC0_SMB6_CLK
BMC_I2C_A_SDA
BMC_I2C_A_SCL
DDR_VREF
NIC_SMBUS_SDA
NIC_SMBUS_SCL
BMC0_SMB2_CLK
BMC0_SMB2_DAT
BMC0_SMB3_CLK
BMC0_SMB3_DAT
BMC0_SMB4_CLK
BMC0_SMB4_DAT
BMC0_SMB5_CLK
BMC0_SMB5_DAT
MemA_13
MemA_14
MemODT
MemCSN
MemRASN
MemCASN
MemBA_0
MemBA_1
MemBA_2
MemDM_0
MemDM_1
MemWEN
MemCK_P
MemCK_N
MemCKE
MemA_10
MemA_11
MemA_12
MemA_0
MemA_1
MemA_2
MemA_3
MemA_4
MemA_5
MemA_6
MemA_7
MemA_8
MemA_9
BMC0_TP15
BMC_MBC_I2C_E_SDA
BMC_MBC_I2C_E_SCL
PU_BMC0_SDA11
PU_BMC0_SDA12
PU_BMC0_SCL12
PU_BMC0_SCL11
BMC0_SMB7_CLK
BMC0_SMB7_DAT
BMC0_SMB8_DAT
BMC0_SMB8_CLK
BMC0_SMB9_DAT
BMC0_SMB9_CLK
PD_PERST_N
TP_LPC_CPU_FRAME_N
TP_BMC0_LPC_LAD0
TP_BMC0_LPC_LAD1
TP_BMC0_LPC_LAD2
TP_BMC0_LPC_LAD3
TP_LPC_CPU_CLKOUT0
TP_IRQ_CPU_SERIAL
DDR_VREF
MemDQ_5
MemDQ_6
MemDQ_7
MemDQ_8
MemDQ_9
MemDQ_10
MemDQ_11
MemDQ_12
MemDQ_13
MemDQ_14
MemDQ_15
MemDQ_0
MemDQ_1
MemDQ_2
MemDQ_3
MemDQ_4
MemDQS_P1
MemDQS_N1
MemDQS_P0
MemDQS_N0
BMC0_PMU_PLTRST_N_BMC
SYS_PWRBTN_N_R
BMC_PWRBTN_N_R
PU_BMC0_SCL11
PU_BMC0_SDA11
PU_BMC0_SDA12
PU_BMC0_SCL12
BMC0_SMB1_DAT
BMC0_SMB14_CLK
BMC0_SMB14_SDA
BMC0_SMB10_DAT
BMC0_SMB10_CLK BMC0_SMB1_CLK
BMC_I2C_B_SDA
BMC_I2C_B_SCL
BMC_I2C_C_SDA
BMC_I2C_C_SCL
BMC_10G_SDA_2
BMC_10G_SCL_2
BMC_SALT4
BMC_SALT3
PU_BMC0_SCL13
PU_BMC0_SDA13
PU_BMC0_SDA13
PU_BMC0_SCL13
FM_BMC_READY_N_R
SYS_RSTBTN_N_R
BMC_RSTBTN_N_R
BMC_MBC_I2C_E_SDA
BMC_MBC_I2C_E_SCL
BMC_MSB_I2C_E_ALERT_#
NIC_SMBUS_ALERT_N
BMC_JTAG_L_R
TP_BMC_GPIOQ6
BMC_LSI_BOARD
BMC_LSI_BOARD
MemDQ_7
MemDQ_6
MemDQ_2
MemDQ_4
MemDQ_3
MemDQ_1
MemDQ_5
MemDQ_0
MemDQ_11
MemDQ_13
MemDQ_12
MemDQ_14
MemDQ_15
MemDQ_10
MemDQ_9
MemDQ_8
MemDQS_N1
MemDQS_P1
MemDQS_N0
MemDQS_P0
MemCSNBMC_DDR3_RST_N
MemA_14
MemA_13
MemODT
MemRASN
MemCASN
MemWEN
MemDM_1
MemDM_0
MemCKE
MemCK_P
MemCK_N
MemBA_0
MemBA_2
MemBA_1
MemA_11
MemA_10
MemA_12
MemA_1
MemA_0
MemA_3
MemA_2
MemA_6
MemA_5
MemA_4
MemA_8
MemA_7
MemA_9
PD_ZQ
DDR_VREF
P1V53_STBY
P1V53_STBY
P3V3_STBY
P3V3_STBY
P1V53_STBY
SYS_PWRBTN_N53
BMC_PWRBTN_N53
BMC_I2C_D_SDA 41,50
BMC_10G_SDA_2 40
BMC_I2C_C_SDA 22,51
BMC_MBC_I2C_E_SDA 33,40
BMC_I2C_A_SDA 39,41,54,55
BMC_10G_SCL_2 40
BMC_MBC_I2C_E_SCL 33,40
BMC_I2C_D_SCL 41,50
BMC_I2C_B_SCL 51
BMC_I2C_C_SCL 22,51
BMC_I2C_A_SCL 39,41,54,55
BMC_I2C_F_SDA 22
BMC_I2C_F_SCL 22
BMC_I2C_B_SDA 51
BMC_I2C_SDA_9 22
BMC_I2C_SCL_9 22
BMC_MSB_I2C_E_ALERT_# 33
I2C_BMC_10G_ALERT# 40
EXP_IOC_BMC_SCL_1418,22
EXP_IOC_BMC_SDA_1418,22
BMC_I2C_SDA_1037,41,54,55
BMC_I2C_SCL_1037,41,54,55
NIC_SMBUS_SDA 33
NIC_SMBUS_SCL 33
NIC_SMBUS_ALERT_N 33
FM_BMC_READY_N53
SYS_RSTBTN_N53
BMC_RSTBTN_N53
BMC_JTAG_L36
PMU_PLTRST_N13,18,31,33,40,44,50,52
BMC_DDR3_RST_N53
Title 
Size Document Number Rev 
Date: Sheet o f 
Honey badger_LSI Base Board 1B
AST1250 I2C DDR LPC
A2
42 71Tuesday, January 20, 2015
Honey badger_LSI Base Board
http://www.wiwynn.com
8F, 90, Sec.1, Xintai 5th Rd., Xizhi Dist.,
New Taipei City 22102, Taiwan (R.O.C.)
Title 
Size Document Number Rev 
Date: Sheet o f 
Honey badger_LSI Base Board 1B
AST1250 I2C DDR LPC
A2
42 71Tuesday, January 20, 2015
Honey badger_LSI Base Board
http://www.wiwynn.com
8F, 90, Sec.1, Xintai 5th Rd., Xizhi Dist.,
New Taipei City 22102, Taiwan (R.O.C.)
Title 
Size Document Number Rev 
Date: Sheet o f 
Honey badger_LSI Base Board 1B
AST1250 I2C DDR LPC
A2
42 71Tuesday, January 20, 2015
Honey badger_LSI Base Board
http://www.wiwynn.com
8F, 90, Sec.1, Xintai 5th Rd., Xizhi Dist.,
New Taipei City 22102, Taiwan (R.O.C.)
R5300R2J-2-GP 1 2
C180
SC1U16V3KX-5GP
1 2
C184
SCD1U16V2KX-3GP
1 2
R2500R2J-2-GP 1 2
R4364K7R2F-GP 1 2
R247 0R2J-2-GP 12
R249 0R2J-2-GP 12
R469 0R2J-2-GP12
R30710KR2F-2-GP 12
R2530R2J-2-GP 1 2
C172
SCD1U16V2KX-3GP
1 2
R244 0R2J-2-GP 12
R230
100KR2F-L1-GP
1 2
R4114K7R2F-GP 1 2
R26910KR2F-2-GP 12
R240 0R2J-2-GP 12
R30610KR2F-2-GP 12
R3144K7R2F-GP 1 2
R245 0R2J-2-GP 12
R31010KR2F-2-GP 12
R236100KR2F-L1-GP 12
C185
SCD1U16V2KX-3GP
1 2
R231
1KR2F-3-GP
1 2
C174
SCD1U16V2KX-3GP
1 2
R3300R2J-2-GP 1 2
R460 0R2J-2-GP 12
R43910KR2F-2-GP NOPOP 12
C178
SCD1U16V2KX-3GP
1 2
R526 0R2J-2-GP 12
R465 0R2J-2-GP 12
R243 0R2J-2-GP 12
C177
SCD01U25V2KX-3GP
1 2
C181
SCD1U16V2KX-3GP
1 2
R238 0R2J-2-GP 12
R44010KR2F-2-GP 12
R26310KR2F-2-GP 12
PCI-Express 
DDR2/DDR3 
LPC 
I2C 
SD/SDIO GPIO 
1 OF 4 U40A
AST1250A1-GP
PERST#K19
PEWAKE#J22
PERXPF21
PERXNF22
PEREFCLKPG22
PEREFCLKNG21 PEREXT D20
PETXP E22
PETXN E21
MDQ0W12
MDQ1V12
MDQ2AB11
MDQ3AA11
MDQ4Y11
MDQ5W11
MDQ6V11
MDQ7Y10
MDQ8V10
MDQ9AB9
MDQ10AA9
MDQ11Y9
MDQ12W9
MDQ13V9
MDQ14Y8
MDQ15W8
MDQS0AB10
MDQS1AA8
MDQS0#AA10
MDQS1#AB8
MCK AB12
MCK# AA12
MCKE Y12
MODT V14
MCS# AA13
MRAS# W13
MCAS# AB13
MWE# Y13
MDM0 W10
MDM1 V8
MBA0 W14
MBA1 AA14
MBA2 Y14
MA0 AB14
MA1 W15
MA2 V15
MA3 Y16
MA4 AB15
MA5 W16
MA6 AA15
MA7 AB18
MA8 AB16
MA9 AA17
MA10 Y15
MA11 AA16
MA12 W17
MA13 Y17
MA14 AB17
MIOZV16
MVREFV13
LCLKB20
LFRAME#A21
LSIRQE17
LAD0 B21
LAD1 A22
LAD2 F19
LAD3 C19
SCL1 K21
SDA1 K22
SCL2 J19
SDA2 J18
GPIOQ0_SCL3 D3
GPIOQ1_SDA3 C2
GPIOQ2_SCL4 B1
GPIOQ3_SDA4 F5
GPIOK0_SCL5 E3
GPIOK1_SDA5 D2
GPIOK2_SCL6 C1
GPIOK3_SDA6 F4
GPIOK4_SCL7 E2
GPIOK5_SDA7 D1
GPIOK6_SCL8 G5
GPIOK7_SDA8 F3
GPIOQ4_SCL14H4
GPIOQ5_SDA14H3
GPIOQ6H2
GPIOQ7H1
GPIOC0_SD1CLK_SCL10C4
GPIOC1_SD1CMD_SDA10B3
GPIOC2_SD1DAT0_SCL11A2
GPIOC3_SD1DAT1_SDA11E5
GPIOC4_SD1DAT2_SCL12D4
GPIOC5_SD1DAT3_SDA12C3
GPIOC6_SD1CD#_SCL13B2
GPIOC7_SD1WP#_SDA13A1
GPIOA4_TIMER5_SCL9 C5
GPIOA5_TIMER6_SDA9 B4
GPIOB0_SALT1 J21
GPIOB1_SALT2 J20
GPIOB2_SALT3 H18
GPIOB3_SALT4 F18
GPIOD0_SD2CLKA18
GPIOD1_SD2CMDD16
GPIOD2_SD2DAT0B17
GPIOD3_SD2DAT1A17
GPIOD4_SD2DAT2C16
GPIOD5_SD2DAT3B16
GPIOD6_SD2CD#A16
GPIOD7_SD2WP#E15
R229
240R2F-1-GP
1 2
R467 0R2J-2-GP 12
TP105 1
R47210KR2F-2-GP 12
TP82 1
R26110KR2F-2-GP 12
R23
10KR2F-2-GP
NOPOP
12
R582 0R2J-2-GP1 2
R2520R2J-2-GP 1 2
R49210KR2F-2-GP 12
R470 0R2J-2-GP 12
R233100KR2F-L1-GP 12
R251 0R2J-2-GP 12
C176
SCD1U16V2KX-3GP
1 2
R26810KR2F-2-GP 12
R468 0R2J-2-GP12
R26010KR2F-2-GP 12
R232
1KR2F-3-GP
1 2
C183
SCD1U16V2KX-3GP
1 2
C171
SCD1U16V2KX-3GP
1 2
TP85 1
TP87 1
TP88 1
C170
SC10U6D3V5KX-4GP
1 2
R241 0R2J-2-GP 12
R47510KR2F-2-GP 12
R30910KR2F-2-GP 12
R54210KR2F-2-GP NOPOP 12
R242 0R2J-2-GP 12
U18
NT5CB64M16FP-DH-GP
ZQL8
VDDB2
VDDD9
VDDG7
VDDK2
VDDK8
VDDN1
VDDN9
VDDR1
VDDR9
A10/APL7
A3N2
A0N3
A12/BC#N7
A5P2
A2P3 A1P7
A4P8
A7R2
A9R3
A11R7
A6R8
A8T8
VSS A9
VSS B3
VSS E1
VSS G8
VSS J2
VSS J8
VSS M1
VSS M9
VSS P1
VSS P9
VSS T1
VSS T9
VSSQ B1
VSSQ B9
VSSQ D1
VSSQ D8
VSSQ E2
VSSQ E8
VSSQ F9
VSSQ G1
VSSQ G9
VDDQC1
VDDQC9
VDDQD2
VDDQE9
VDDQF1
VDDQH2
VDDQH9
VDDQA1
VDDQA8
RAS#J3
CAS#K3
WE#L3
DQU0 D7
DQU1 C3
DQU2 C8
DQU3 C2
DQU4 A7
DQU5 A2
DQU6 B8
DQU7 A3
DQL0 E3
DQL1 F7
DQL2 F2
DQL3 F8
DQL4 H3
DQL5 H8
DQL6 G2
DQL7 H7
VREFDQH1
VREFCAM8
BA0M2
BA1N8
BA2M3
CKJ7
CK#K7
CKEK9
DMLE7
DMUD3
DQSL F3
DQSL# G3
DQSU C7
DQSU# B7
NC#T7 T7NC#T3 T3NC#M7 M7NC#L9 L9NC#L1 L1NC#J9 J9NC#J1 J1
ODTK1
CS#L2
RESET#T2
R4374K7R2F-GP 1 2
R471 0R2J-2-GP 12
R259100KR2F-L1-GP 12
R235100KR2F-L1-GP 12
R44110KR2F-2-GP 12
R44710KR2F-2-GP 12
R3280R2J-2-GP 1 2
R234100KR2F-L1-GP 12
C173
SCD1U16V2KX-3GP
1 2
R258100KR2F-L1-GP 12
R237100KR2F-L1-GP 12
C182
SCD1U16V2KX-3GP
1 2
R20
100R2F-L1-GP-U
1 2
R26210KR2F-2-GP 12
C179
SCD01U25V2KX-3GP
1 2
C175
SCD1U16V2KX-3GP
1 2
R43810KR2F-2-GP NOPOP 12
R239 0R2J-2-GP 12
R461 0R2J-2-GP 12
R246 0R2J-2-GP 12
R462 0R2J-2-GP 12
R466 0R2J-2-GP 12
R44810KR2F-2-GP 12



5
5
4
4
3
3
2
2
1
1
D D
C C
B B
A A
BMC Flash SKT 
Default 24bit Addr 
32bit Addr can be set by command 
BMC SPI Flash 
BMC SPI 2nd Flash 
TP_GPIOH3
TP_GPIOH4
RMII0_BMC_C_RX_ER
TP_GPIOH5
RMII0_BMC_C_PHY_TXD1
RMII0_BMC_C_TX_EN
RMII0_BMC_C_PHY_TXD0RMII0_PHY_BMC_C_RXD0
RMII0_PHY_BMC_C_RXD1
RMII0_BMC_C_CRS_DV
PU_IBMC_BT_HOLD_N
FLA_CS_R
ROMD2_R
ROMD0_R
FLA_WPN
ROMD1_R
TP_GPIOH6
TP_GPIOH7
BMC_RXD5_R BMC_TXD5_R
FLA_CS
BMC_EN_0V955_R
FLA_CS
ROMD1_R
ROMD0_R
ROMD2_R
ROMD1
ROMD0
ROMD2
FLA_CS_R
TP_BMC_GPIOI0
ROMA5
ROMA4
ROMA3
ROMA2
ROMA1
ROMA0
ROMA10
ROMA9
ROMA8
ROMA7
ROMA6
ROMA14
ROMA13
ROMA12
ROMA11
ROMA20
ROMA19
ROMA18
ROMA17
ROMA16
ROMA15
ROMA22
ROMA21
ROMA23
TP_BMC_GPIOR5
TP_BMC_GPIOR4
BMC_EN_P3V3_R
ROMD1_R
ROMD2_R
FLA_CS_R
ROMD0_R
FLA_WPN
PU_IBMC_BT_HOLD_N
ROMD1
ROMD2
ROMD3
ROMD4
ROMD5
ROMD6
ROMD7
ROMD0
TP_GPIOH2
TP_BMC_GPIOM0
TP_BMC_GPIOM1
TP_BMC_GPIOM2
BMC_RXD1
BMC_TXD1
BMC_1V8_C_EN_R
PWGD_P0V955_C_PG_RPWGD_P0V9_E_PG_R
OSC_OE
125_GTX BMC_MAC2_RGMIICK
TP_BMC_GPIOL0
TP_BMC_GPIOL1
TP_BMC_GPIOL2
TP_BMC_GPIOL3
TP_BMC_GPIOL4
TP_BMC_GPIOL5
TP_BMC_GPIOL6
TP_BMC_GPIOL7
TP_BMC_GPIOM3
TP_BMC_GPIOM4
TP_BMC_GPIOM6
TP_BMC_GPIOM5
TP_BMC_GPIOM7
TP_BMC_GPIOF0
TP_BMC_GPIOF2
TP_BMC_GPIOF4
TP_BMC_GPIOF3
TP_BMC_GPIOF1
TP_BMC_GPIOF5
TP_BMC_GPIOE0
TP_BMC_GPIOE1
TP_BMC_GPIOE2
TP_BMC_GPIOE3
TP_BMC_GPIOE4
TP_BMC_GPIOE5
TP_BMC_GPIOR1
TP_BMC_GPIOR2
FLA_CS_1_R
TP_BMC_GPIOR4
TP_BMC_GPIOR5
TP_BMC_GPIOR3
TP_BMC_GPIOU2
TP_BMC_GPIOU3
TP_BMC_GPIOA6
TP_BMC_GPIOA7
TP_BMC_GPIOT7TP_BMC_GPIOV3
CPU_BMC_UART_TX
CPU_BMC_UART_RX
TP_BMC_GPIOF6
TP_BMC_GPIOF7
FLA_CS_1
FLA_WPN
PU_IBMC_BT_HOLD_N
CLK_50M_BMC_NCSI_R
BMC_RXCK_R
ROMD1_RROMD1_R_R
ROMD0_RROMD0_R_R
ROMD2_R ROMD2_R_R
FLA_CS_1
CLK_50M_BMC0
RMII_PHY_BMC_RXD0
RMII_PHY_BMC_RXD1
RMII_BMC_CRS_DV
RMII_BMC_TX_EN
RMII_BMC_PHY_TXD0
RMII_BMC_PHY_TXD1
RMII_BMC_MDC
RMII_BMC_MDIO
BMC_RXD5BMC_R_RXD5
BMC_TXD5BMC_R_TXD5
P3V3_STBY
P3V3_STBY
P3V3_STBY
P3V3_STBY
P3V3_STBYP3V3_STBY
P3V3_STBY
P3V3_STBY
P5V_STBY
BMC_RST_EXPANDER25
BMC_EN_P3V3 62
PMU_WAKE_N40
BMC_EN_0V955_C 63
USB_OCS_N150
RMII_BMC_PHY_TXD0 48
RMII_BMC_PHY_TXD1 48
RMII_BMC_TX_EN 48
RMII_BMC_MDC 48
RMII_BMC_MDIO 48
RMII_PHY_BMC_RXD048
RMII_PHY_BMC_RXD148
RMII_BMC_CRS_DV48
RMII_BMC_RX_ER48
ROMD446
ROMA[23..0] 46
ROMD346
ROMD246
ROMD746
ROMD646
ROMD546
ROMD1_R46
ROMD0_R46
CLK_50M_BMC048
BMC_RXD552 BMC_TXD5 52
BMC_ID_LED31
CPU_BMC_UART_TX52
CPU_BMC_UART_RX52
BMC_1V8_C_EN 65
PG_STAT_P0V955_C 63P0V9_E_PG25,33,62,64
NCSI_10G_RX_ER40
NCSI_10G_RXD140
NCSI_10G_RXD040
CLK_50M_BMC_NCSI48
NCSI_10G_RCSDV40
NCSI_10G_TXD0 40
NCSI_10G_TXEN 40
NCSI_10G_TXD1 40
Title 
Size Document Number R e v 
Date: Sheet 
o f 
Honey badger_LSI Base Board 1B
AST1250 UART LAN SPI
A3
43 71Tuesday, January 20, 2015
Honey badger_LSI Base Board
http://www.wiwynn.com
8F, 90, Sec.1, Xintai 5th Rd., Xizhi Dist.,
New Taipei City 22102, Taiwan (R.O.C.)
Title 
Size Document Number R e v 
Date: Sheet 
o f 
Honey badger_LSI Base Board 1B
AST1250 UART LAN SPI
A3
43 71Tuesday, January 20, 2015
Honey badger_LSI Base Board
http://www.wiwynn.com
8F, 90, Sec.1, Xintai 5th Rd., Xizhi Dist.,
New Taipei City 22102, Taiwan (R.O.C.)
Title 
Size Document Number R e v 
Date: Sheet 
o f 
Honey badger_LSI Base Board 1B
AST1250 UART LAN SPI
A3
43 71Tuesday, January 20, 2015
Honey badger_LSI Base Board
http://www.wiwynn.com
8F, 90, Sec.1, Xintai 5th Rd., Xizhi Dist.,
New Taipei City 22102, Taiwan (R.O.C.)
R287
0R2J-2-GP
1 2
SCN8
JWT-CON4-S24-GP
1
2
3
4
TP95
1
TP1121
TP151 1
TP1151
TP89 1
R486
2K2R2J-2-GP1 2
R292 0R2J-2-GP 12
TP91
1
C333 
1 2
R288
47KR2F-GP
NOPOP
1 2
BMC NOR/NAND/SPI System 
 UART 
BMC UART 
MAC1 
MAC2 
System 
  SPI 
2 OF 4 U40B
AST1250A1-GP
ROMA0 R20
ROMA1 R21
ROMA2_GPIOZ0_VPOB0 R22
ROMA3_GPIOZ1_VPOB1 P18
ROMA4_GPIOZ2_VPOB2 P19
ROMA5_GPIOZ3_VPOB3 P20
ROMA6_GPIOZ4_VPOB4 P21
ROMA7_GPIOZ5_VPOB5 P22
ROMA8_GPIOZ6_VPOB6 M19
ROMA9_GPIOZ7_VPOB7 M20
ROMA10_GPIOAA0_VPOG0 M21
ROMA11_GPIOAA1_VPOG1 M22
ROMA12_GPIOAA2_VPOG2 L18
ROMA13_GPIOAA3_VPOG3 L19
ROMA14_GPIOAA4_VPOG4 L20
ROMA15_GPIOAA5_VPOG5 L21
ROMA16_GPIOAA6_VPOG6 T18
ROMA17_GPIOAA7_VPOG7 N18
ROMA18_GPIOAB0_VPOR0 N19
ROMA19_GPIOAB1_VPOR1 M18
ROMA20_GPIOAB2_VPOR2 N22
ROMA21_GPIOAB3_VPOR3 N20
ROMA22_GPIOS6_VPOR4 L22
ROMA23_GPIOS7_VPOR5 K18
GPIOR4_ROMA24_VPOR6 V21
GPIOR5_ROMA25_VPOR7 W22
ROMCS0#R19
GPIOR0_ROMCS1#V20
GPIOR1_ROMCS2#W21
GPIOR2_ROMCS3#Y22
GPIOR3_ROMCS4#U19
ROMOE#_GPIOS4R18
ROMWE#_GPIOS5N21
ROMD0T22
ROMD1T21
ROMD2T20
ROMD3U22
ROMD4_GPIOS0_VPODEU21
ROMD5_GPIOS1_VPOHST19
ROMD6_GPIOS2_VPOVSV22
ROMD7_GPIOS3_VPOCLKU20
GPIOH0_ROMD8_NCTS6A8
GPIOH1_ROMD9_NDCD6C7
GPIOH2_ROMD10_NDSR6B7
GPIOH3_ROMD11_NRI6A7
GPIOH4_ROMD12_NDTR6D7
GPIOH5_ROMD13_NRTS6B6
GPIOH6_ROMD14_TXD6A6
GPIOH7_ROMD15_RXD6E7
GPIOL0_NCTS1U1
GPIOL1_NDCD1_VPIDET5
GPIOL2_NDSR1_VPIODDU3
GPIOL3_NRI1_VPIHSV1
GPIOL4_NDTR1_VPIVSU4
GPIOL5_NRTS1_VPICLKV2
GPIOL6_TXD1_VPIB0W1
GPIOL7_RXD1_VPIB1U5
GPIOM0_NCTS2_VPIB2 V3
GPIOM1_NDCD2_VPIB3 W2
GPIOM2_NDSR2_VPIB4 Y1
GPIOM3_NRI2_VPIB5 V4
GPIOM4_NDTR2_VPIB6 W3
GPIOM5_NRTS2_VPIB7 Y2
GPIOM6_TXD2_VPIB8 AA1
GPIOM7_RXD2_VPIB9 V5
GPIOE0_NCTS3D15
GPIOE1_NDCD3C15
GPIOE2_NDSR3B15
GPIOE3_NRI3A15
GPIOE4_NDTR3E14
GPIOE5_NRTS3D14
GPIOE6_TXD3C14
GPIOE7_RXD3B14
GPIOF0_NCTS4 D18
GPIOF1_NDCD4_SIOPBI# B19
GPIOF2_NDSR4_SIOPWRGD A20
GPIOF3_NRI4_SIOPBO# D17
GPIOF4_NDTR4 B18
GPIOF5_NRTS4_SIOSCI# A19
GPIOF6_TXD4 E16
GPIOF7_RXD4 C17
RXD5G1 TXD5 H5
RGMII1TXD3_GPIOT5 A13RGMII1TXD2_GPIOT4 E12RGMII1TXD1_RMII1TXD1_GPIOT3 D12RGMII1TXD0_RMII1TXD0_GPIOT2 C12RGMII1TXCTL_GPIOT1 B12RGMII1TXCK_RMII1TXEN_GPIOT0 A12RGMII1RXCK_RMII1RCLK_GPIOU4E11
RGMII1RXCTL_GPIOU5D11
RGMII1RXD0_RMII1RXD0_GPIOU6C11
RGMII1RXD1_RMII1RXD1_GPIOU7B11
RGMII1RXD2_RMII1CRSDV_GPIOV0A11
RGMII1RXD3_RMII1RXER_GPIOV1E10
RGMII2TXD3_GPIOU3 D10RGMII2TXD2_GPIOU2 C10RGMII2TXD1_RMII2TXD1_GPIOU1 B10RGMII2TXD0_RMII2TXD0_GPIOU0 A10RGMII2TXCTL_GPIOT7 E9RGMII2TXCK_RMII2TXEN_GPIOT6 D9RGMII2RXCK_RMII2RCLK_GPIOV2C9
RGMII2RXCTL_GPIOV3B9
RGMII2RXD0_RMII2RXD0_GPIOV4A9
RGMII2RXD1_RMII2RXD1_GPIOV5E8
RGMII2RXD2_RMII2CRSDV_GPIOV6D8
RGMII2RXD3_RMII2RXER_GPIOV7C8
RGMIICKB8
GPIOR6_MDC1 C6
GPIOR7_MDIO1 A5
GPIOA6_TIMER7_MDC2 A3
GPIOA7_TIMER8_MDIO2 D5
GPIOI0_SYSCS#C22
GPIOI1_SYSCKG18
GPIOI2_SYSDOD19
GPIOI3_SYSDIC20
GPIOI4_SPICS0#_VBCS# B22
GPIOI5_SPICK_VBCK G19
GPIOI6_SPIDO_VBDO C18
GPIOI7_SPIDI_VBDI E20
TP141 1
R474 0R2J-2-GP 12
U19
DNU/SIO31
VCC 2
CS#7
SO/SIO18
WP#/SIO29
GND10
SI/SIO015
SCLK16
RESET#3
NC#4 4
NC#5 5
NC#6 6
NC#11 11
NC#12 12
NC#13 13
NC#14 14
R2860R2J-2-GP 1 2
TP1761
TP961
R615
2K2R2J-2-GP
NOPOP
1 2
SR942 0R2J-2-GP1 2
R279 0R2J-2-GP 12
TP137 1
TP102 1
R331 0R2J-2-GP 12
TP1161
R264 
2K2R2J-2-GP 
1 2
TP1831
TP1751
R539 0R2J-2-GP 12
TP1521
R679 0R2J-2-GP 12
C7788
SCD1U16V2KX-3GP
1 2
TP110 1
TP981
SR941 0R2J-2-GP1 2
TP140 1
R445 0R2J-2-GPNOPOP 12
TP146 1
C186 
1 2
TP144 1
R295 0R0402-PAD-1-GP1 2
R422
2K2R2J-2-GP
NOPOP
1 2
R267 
2K2R2J-2-GP 
NOPOP
1 2
TP139 1
R463 0R2J-2-GPNOPOP 12
R442 0R2J-2-GPNOPOP 12
TP92
1
R616
2K2R2J-2-GP
NOPOP
1 2
R6720R2J-2-GP 1 2
R7888 47R2F-GP
NOPOP
1 2
TP158 1
R464 0R2J-2-GPNOPOP 12
R7789
49D9R2F-GP
1 2
SC1307 
SCD1U16V2KX-3GP 
1 2
R294 0R0402-PAD-1-GP1 2
R684
0R2J-2-GP
NOPOP1 2
TP101 1
TP1361TP142 1
TP1561
R620 0R2J-2-GPNOPOP 12
TP97
1
TP100 1
R291 0R2J-2-GPNOPOP 12
R646 0R2J-2-GPNOPOP 12
SKT3
SKT-SPI16P-GP-U
1
2
3
4
5
6
7
8
16
15
14
13
12
11
10
9
TP104 1
TP90 1
X10
OSC-125MHZ-3-GP
NOPOP
OE 1GND 2OUT 3VDD 4
TP93
1
TP1531
TP1551
TP103 1
TP1351
R540 0R2J-2-GP 12
TP150 1
R444 0R2J-2-GPNOPOP 12
TP1341
TP94
1
R682
0R2J-2-GP
NOPOP 12
R476 0R2J-2-GP 12
TP1541
TP1141
R687 0R2J-2-GPNOPOP 12
TP1131
R265 
0R0402-PAD-1-GP 
1 2
TP1821
TP143 1
R283 0R2J-2-GP 12
TP1741
R681 0R2J-2-GPNOPOP 12
R6710R2J-2-GP 1 2
R296 0R0402-PAD-1-GP1 2
R5410R2J-2-GP 1 2
TP1331
R421
2K2R2J-2-GP
1 2
R2840R2J-2-GP 1 2
TP138 1
R2820R2J-2-GP 1 2
TP1111
R280 0R2J-2-GP 12
R680 0R2J-2-GPNOPOP 12
R285 0R2J-2-GP 12
R293 0R0402-PAD-1-GP1 2
R266 
2K2R2J-2-GP 
1 2
R281 0R2J-2-GP 12
U195
W25Q128FVSIG-GP
NOPOP
CS#1
DO/IO12
WP#/IO23
GND4 DI/IO0 5CLK 6HOLD#/RESET#/IO3 7VCC 8
TP1181



5
5
4
4
3
3
2
2
1
1
D D
C C
B B
A A
BMC0_I2C_IO_EXP_RESET#
RST_BMC_DDR3_R_N
BMC0_SRST_N
JTAG_BMC_TRST_N
BMC0_JTAG_RTCK
FM_BMC_RESET_N
BMC0_TACH11
HB0_R_IN0
HB0_R_IN1
HB0_R_IN2
BMC0_TACH12
BMC0_TACH13
BMC0_TACH15
ADC_P1V5_E_BMC
BMC0_ENTEST1
OSC0_AS_CLKIN
OSC2_OUT
OSC2_CONT
DP_RST_N_R
LPCRST0_N
FCB_HW_REVISION
DPB_HW_REVISION
MB0_PRESNET#
BMC0_LED_DR_R_LED0
FAN_PWM_PCIe_BMC
LOW_HEX_1
LOW_HEX_2
ADC_P1V8_STBY_BMC
ADC0_12V_BMC
ADC_P1V5_C_BMC
ADC_P3V3_STBY_BMC
ADC_P5V_STBY_BMC
ADC_P0V955_C_BMC
ADC_P0V9_E_BMC
EXP_TRAY_ID_BMC
LOW_HEX_3
PD_USB2VRES
HIGH_HEX_0
HIGH_HEX_1
HIGH_HEX_2
HIGH_HEX_3
PEER_TRAY_BMC
LOW_HEX_0
EXP_ID_BMC
CONN_10G_PRSNT2_N
JTAG_BMC_TRST_N
JTAG_BMC_TDO
JTAG_BMC_TMS
JTAG_BMC_TDI
JTAG_BMC_TCK
BMC0_JTAG_RTCK
HDD_PRE_INT_R
PECI0_R
TP_BMC_GPIOJ4
TP_BMC_GPIOJ5
TP_BMC_GPIOJ6
TP_BMC_GPIOJ7
BMC0_SRST_N
DP_BMC_EXP_RST_N_R
DP_BMC_CPU_RST_N_R
BMC_USB2_HDP
BMC_USB2_HDN
BMC_USB1_HDN
BMC_USB1_HDP
BMC_USB1_HDN2
BMC_USB1_HDP2
BMC0_LED_DR_R_LED1
JTAG_BMC_TDI
JTAG_BMC_TMS
JTAG_BMC_TCK
JTAG_BMC_TDO
BMC_JTAG_L_EN_R
BMC0_TACH14
BMC_EN_CPU_RESET_CONTROL
TP_BMC_GPIOO7
BMC0_TACH10
TP_BMC0_TACH8
BMC0_TACH9
BMC_FW_DET_BOARD_VER_0
BMC_FW_DET_BOARD_VER_2
BMC_FW_DET_BOARD_VER_1
BMC_FW_DET_BOARD_VER_0
BMC_FW_DET_BOARD_VER_1
BMC_FW_DET_BOARD_VER_2
TP_BMC_GPIOB7
P3V3_STBY
P1V53_STBY
P3V3_STBY
P1V26_STBY
P3V3_STBY
P3V3_STBY P3V3_STBY P3V3_STBY P3V3_STBY P3V3_STBY P3V3_STBY
P3V3_STBY
P1V26_STBY_PG60,65
FM_BMC_RESET_N48
BMC_DDR3_RST_N 42
PEER_TRAY_R23,38
ADC_P1V5_E41,47
FM_BMC_RESET_N48
P1V8_STBY_PG58,59
FAN_PWM_PCIe 23,38
LED_DR_LED0 41
I2C_IO_EXP_RESET# 37
BMC_SELF_TRAY 38
PEER_1B_2B_HB23,38
PEER_1A_2A_HB23,38
HB_B_SIDE_IN38
ADC_P1V5_C41,47
ADC_12V41,47
ADC_P3V3_STBY41,47
ADC_P5V_STBY41,47
ADC_P1V8_STBY41,47
ADC_P0V955_C41,47
ADC_P0V9_E41,47
FCB_HW_REVISION 23,38
DPB_HW_REVISION 23,38
SAS_SEB_PEER_PRSNT_BMC 38
LOW_HEX_0 52
LOW_HEX_1 52
LOW_HEX_2 52
LOW_HEX_3 52
HIGH_HEX_0 52
HIGH_HEX_1 52
HIGH_HEX_2 52
EXP_TRAY_ID23,38
HIGH_HEX_3 52
DP_RST_N52
PRSNT_CONTROL_BMC 33
EXP_ID38
HB_OUT_BMC32
HB_EXP_TO_BMC32
CONN_10G_PRSNT2_N40
BMC_HDD_PRE_INT_N37
HSC_MSB_ALERT_N 54
DEBUG_LED_SW 52
DP_BMC_EXP_RST_N25
DP_BMC_CPU_RST_N53
JTAG_BMC_TRST_N36
JTAG_BMC_TDI36
JTAG_BMC_TMS36
JTAG_BMC_TCK36
JTAG_BMC_TDO36
USB_P2_DP 50
USB_P2_DN 50
USB_P3_DP 50
USB_P3_DN 50
USB_P4_DP 50
USB_P4_DN 50
LED_DR_LED1 31,41
BMC_JTAG_L_EN36
BMC_UART_SWITCH_152
BMC_UART_SWITCH_252
UART COUNT52
SVR_ID033
BMC_DEBUG_OE_2_N52
PMU_PLTRST_N 13,18,31,33,40,42,50,52
BMC_ENCLOSURE_LED31
BMC_DEBUG_OE_1_N52
BMC_EN_CPU_RESET_CONTROL53
Title 
Size Document Number R e v 
Date: Sheet 
o f 
Honey badger_LSI Base Board 1B
AST1250 FAN ADC VGA
A3
44 71Tuesday, January 20, 2015
Honey badger_LSI Base Board
http://www.wiwynn.com
8F, 90, Sec.1, Xintai 5th Rd., Xizhi Dist.,
New Taipei City 22102, Taiwan (R.O.C.)
Title 
Size Document Number R e v 
Date: Sheet 
o f 
Honey badger_LSI Base Board 1B
AST1250 FAN ADC VGA
A3
44 71Tuesday, January 20, 2015
Honey badger_LSI Base Board
http://www.wiwynn.com
8F, 90, Sec.1, Xintai 5th Rd., Xizhi Dist.,
New Taipei City 22102, Taiwan (R.O.C.)
Title 
Size Document Number R e v 
Date: Sheet 
o f 
Honey badger_LSI Base Board 1B
AST1250 FAN ADC VGA
A3
44 71Tuesday, January 20, 2015
Honey badger_LSI Base Board
http://www.wiwynn.com
8F, 90, Sec.1, Xintai 5th Rd., Xizhi Dist.,
New Taipei City 22102, Taiwan (R.O.C.)
R334
47KR2F-GP
NOPOP
1 2
R3200R2J-2-GP 1 2
R6130R2J-2-GP 1 2
R3190R2J-2-GP 1 2
TP177 1
R4490R2J-2-GP 1 2
R303 0R2J-2-GP 12
TP191 1
C187
SCD1U16V2KX-3GP
1 2
TP173 1
TP181 1
R333
47KR2F-GP
1 2
R5330R2J-2-GP NOPOP1 2
TP180 1
VGA 
USB 
PECI 
FAN 
ADC 
JTAG 
SGPIO 
GPIO 
MISC 
3 OF 4 U40C
AST1250A1-GP
ENTESTE4
GPIOY3_SIOONCTRL# K20
CLKINAB22
SRST#W20
DACB R4
DACG R3
DACR R2
DDCCLK_GPIOJ6 T2
DDCDAT_GPIOJ7 T1
VGAHS_GPIOJ4 T4
VGAVS_GPIOJ5 U2
GPIOO0_TACH0_VPIG8V6
GPIOO1_TACH1_VPIG9Y5
GPIOO2_TACH2_VPIR0AA4
GPIOO3_TACH3_VPIR1AB3
GPIOO4_TACH4_VPIR2W6
GPIOO5_TACH5_VPIR3AA5
GPIOO6_TACH6_VPIR4AB4
GPIOO7_TACH7_VPIR5V7
GPION4_PWM4_VPIG4 W5
GPION5_PWM5_VPIG5 Y4
GPION6_PWM6_VPIG6 AA3
GPION7_PWM7_VPIG7 AB2
USB2AV33 W18
USB2AVSS Y19USB2VRES AA20
USB2_DP/USB2_HDP AB21
USB2_DN/USB2_HDN AB20
USB11_HDN J2USB11_HDP J1
USB11_DP/USB11_HDP2 K4
USB11_DN/USB11_HDN2 K3
PECI AA21PECIVDD V19
ADC0_GPIW0L5
ADC1_GPIW1L4
ADC2_GPIW2L3
ADC3_GPIW3L2
ADC4_GPIW4L1
ADC5_GPIW5M5
ADC6_GPIW6M4
ADC7_GPIW7M3
ADC8_GPIX0M2
ADC9_GPIX1M1
ADC10_GPIX2N5
ADC11_GPIX3N4
ADC12_GPIX4N3
ADC13_GPIX5N2
ADC14_GPIX6N1
ADC15_GPIX7P5
GPIOJ0_SGPMCK J5
GPIOJ1_SGPMLD J4
GPIOJ2_SGPMO K5
GPIOJ3_SGPMI J3
NTRSTE1
TDI_BDMF1
TMSG2
TCKF2
RTCKG4
TDOG3 GPIOG0_SGPSCK A14
GPIOG1_SGPSLD E13
GPIOG2_SGPSI0 D13
GPIOG3_SGPSI1 C13
GPIOG5_WDTRST2_USBCKIY21
GPIOG6_FLBUSY#AA22
GPIOG7_FLWP#U18
GPIOG4_WDTRST1_OSCCLKB13
GPIOA0_MAC1LINKD6
GPIOA1_MAC2LINKB5
GPIOA2_TIMER3A4
GPIOA3_TIMER4E6
GPIOB4_LPCRST# E19
GPIOB5_LPCPD#_LPCSMI# H19
GPIOB6_LPCPME# H20
GPIOB7_EXTRST#_SPICS1# E18
GPIOP0_TACH8_VPIR6Y6
GPIOP1_TACH9_VPIR7AB5
GPIOP2_TACH10_VPIR8W7
GPIOP3_TACH11_VPIR9AA6
GPIOP4_TACH12AB6
GPIOP5_TACH13Y7
GPIOP6_TACH14_BMCINTAA7
GPIOP7_TACH15_FLACKAB7
GPION0_PWM0_VPIG0 W4
GPION1_PWM1_VPIG1 Y3
GPION2_PWM2_VPIG2 AA2
GPION3_PWM3_VPIG3 AB1
GPIOY1_SIOS5# F20GPIOY0_SIOS3# C21
GPIOY2_SIOPWREQ# G20
R297
4K7R2F-GP
1 2
R6560R2J-2-GP 1 2
TP179 1
R491
0R2J-2-GP
1 2
R304 0R2J-2-GP 12
TP172 1
TP178 1
R3150R2J-2-GP 1 2
R801
4K7R2F-GP
1 2
U25
SN74LVC1G07DCKRG4-2-GP
GND3 A2 NC#11 VCC 5
Y 4
R3210R2J-2-GP 1 2
R6140R2J-2-GP 1 2
SR853
4K75R2F-1-GP
NOPOP
1 2
OSC1
OSC-48MHZ-28-GP
OE1
GND2 OUTPUT 3VDD 4
R335
10KR2F-2-GP
12
R4520R2J-2-GP NOPOP1 2
R537 0R2J-2-GP 12
R607 0R2J-2-GP 12
R3320R2J-2-GP 12
R562 0R2J-2-GP 12
C272
SCD1U16V2KX-3GP
1 2
R6700R2J-2-GP 1 2
R3130R2J-2-GP 1 2
TP1621
R3160R2J-2-GP 1 2
TP1611
R804
4K7R2F-GP
1 2
R3180R2J-2-GP 1 2
R4500R2J-2-GP 1 2
R5340R2J-2-GP NOPOP1 2
SR944
4K75R2F-1-GP
1 2
R3220R2J-2-GP 1 2
R612 0R2J-2-GP 12
R6580R2J-2-GP 1 2
R3730R2J-2-GP 1 2
R8000R2J-2-GP NOPOP1 2
TP1591
SR849
4K75R2F-1-GP
NOPOP
1 2
SR847
4K75R2F-1-GP
1 2
R327100KR2F-L1-GP 1 2
R317
8K2R2J-3-GP
1 2
SR943
4K75R2F-1-GP
1 2
R523 0R2J-2-GP 12
R299 0R2J-2-GP1 2
R802
4K7R2F-GP
1 2
R4510R2J-2-GP NOPOP1 2
TP145 1
TP1631R538 0R2J-2-GP 12
R336
0R2J-2-GP
NOPOP
1 2
C188
SC1U10V3KX-4GP-U
NOPOP
1 2
R300 0R2J-2-GPNOPOP1 2
R806 0R2J-2-GP 12
R5830R2J-2-GP 1 2
R302 0R2J-2-GP 12
TP1601
R324
10KR2F-2-GP
1 2
R805 0R2J-2-GP 12
R125
0R2J-2-GP
1 2
R301
10KR2F-2-GP
12
R489
4K7R2F-GP
1 2
R3080R2J-2-GP 12
R803
4K7R2F-GP
1 2
R5840R2J-2-GP 1 2
SR852
4K75R2F-1-GP
NOPOP
1 2
R3290R2J-2-GP 12
R3110R2J-2-GP NOPOP1 2
R298
10R2F-L-GP
1 2
R799
4K7R2F-GP
1 2



5
5
4
4
3
3
2
2
1
1
D D
C C
B B
A A
DACRSET
ADCAV33
ADCVREFFN
ADCVREFFP
ADCVREXT
V1PLLAV12
MPLLAV33
V1PLLAV12
MPLLAV33
ADCAV33
P1V26_STBY
P3V3_STBY
P1V26_STBY
P1V53_STBY
P3V3_STBY
P1V53_STBY
P1V26_STBY
P3V3_STBY
P3V3_STBY
P1V26_STBY
P3V3_STBY
P3V3_STBY
Title 
Size Document Number R e v 
Date: Sheet 
o f 
Honey badger_LSI Base Board 1B
AST1250 Power
A3
45 71Tuesday, January 20, 2015
Honey badger_LSI Base Board
http://www.wiwynn.com
8F, 90, Sec.1, Xintai 5th Rd., Xizhi Dist.,
New Taipei City 22102, Taiwan (R.O.C.)
Title 
Size Document Number R e v 
Date: Sheet 
o f 
Honey badger_LSI Base Board 1B
AST1250 Power
A3
45 71Tuesday, January 20, 2015
Honey badger_LSI Base Board
http://www.wiwynn.com
8F, 90, Sec.1, Xintai 5th Rd., Xizhi Dist.,
New Taipei City 22102, Taiwan (R.O.C.)
Title 
Size Document Number R e v 
Date: Sheet 
o f 
Honey badger_LSI Base Board 1B
AST1250 Power
A3
45 71Tuesday, January 20, 2015
Honey badger_LSI Base Board
http://www.wiwynn.com
8F, 90, Sec.1, Xintai 5th Rd., Xizhi Dist.,
New Taipei City 22102, Taiwan (R.O.C.)
C218
SC1U10V2KX-1GP
1 2
C202
SCD1U16V2KX-3GP
1 2
C215
SC1U10V2KX-1GP
1 2
C204
SC1U10V3KX-4GP-U
1 2
C199
SC1U10V3KX-4GP-U
1 2
C210
SC1U6D3V3KX-2GP
1 2
L4
MMZ2012S601ATA1N-GP
68.00109.171
1 2
C219
SC1U10V3KX-4GP-U
1 2
C192
SC1U6D3V3KX-2GP
1 2
C197
SC1U10V3KX-4GP-U
1 2
4 OF 4 U40D
AST1250A1-GP
GND J10
GND J11
GND J12
GND J13
GND J14
GND J9
GND K10
GND K11
GND K12
GND K13
GND K14
GND K9
GND L10
GND L11
GND L12
GND L13
GND L14
GND L9
GND M10
GND M11
GND M12
GND M13
GND M14
GND M9
GND N10
GND N11
GND N12
GND N13
GND N14
GND N9
GND P10
GND P11
GND P12
GND P13
GND P14
GND P9
R2VDDF8
R2VDDF9
R1VDDF10
R1VDDF11
MVDDU10
MVDDU11
MVDDU14
MVDDU15
PV33DF12
PV33DF13
PV33DH6
PV33DH17
PV33DJ6
PEAV33J17
PV33DM6
PV33DM17
PV33DN6
PV33DN17
PV33DU8
PV33DU9
IV12D F14
IV12D F15
IV12D K6
PEAV12 K17
IV12D L6
IV12D L17
IV12D P6
IV12D P17
IV12D R6
IV12D R17
IV12D U12
IV12D U13
MPLLAV33AB19
HPLLAV33V17
MPLLDV12Y18
V1PLLAV12W19
V2PLLAV12Y20
PLLVSS AA19
PLLVSS AA18
PLLVSS V18
DACAV33P1
DACAVSS R5
DACRSETR1
DACDV33T3
ADCVREFNK2
ADCVREFPK1
ADCAVSS P4
ADCAV33P3
ADCREXTP2
NC#H21H21
NC#H22H22
PEAGND D21
PEAGND D22
C200
SC1U10V3KX-4GP-U
1 2
C196
SC100P50V2JN-3GP
1 2
C209
SC220P50V2KX-3GP
1 2
R337 49K9R2F-L-GP1 2
C198
SC1U10V3KX-4GP-U
1 2
R338
2K74R3F-GP
1 2
C203
SC100P50V2JN-3GP
1 2
C216
SC1U10V2KX-1GP
1 2
C189
SCD1U16V2KX-3GP
NOPOP
1 2
C211
SC220P50V2KX-3GP
1 2
C194
SC1U6D3V3KX-2GP
1 2
C206
SC1U10V2KX-1GP
1 2
C212
SC1U10V2KX-1GP
1 2
C193
SC100P50V2JN-3GP
1 2
C214
SC1U10V2KX-1GP
1 2
C201
SC1U6D3V3KX-2GP
1 2
C205
SC1U10V2KX-1GP
1 2
L5
MMZ2012S601ATA1N-GP
68.00109.171
1 2
C217
SC1U10V2KX-1GP
1 2
C208
SC1U10V2KX-1GP
1 2
C195
SCD1U16V2KX-3GP
1 2
L6
MMZ2012S601ATA1N-GP
68.00109.171
1 2
C190
SCD1U16V2KX-3GP
NOPOP
1 2
C191
SCD1U16V2KX-3GP
NOPOP
1 2
C213
SC1U10V2KX-1GP
1 2
C207
SC1U10V3KX-4GP-U
1 2



5
5
4
4
3
3
2
2
1
1
D D
C C
B B
A A
1-2 (Default) 
2-3 
BMC enable 
BMC disable 
ROMD0_R
ROMD2
ROMD3
ROMD4
ROMD5
ROMD1_R
ROMD6
ROMD7
ROMA11
ROMA12
ROMA13
ROMA14
ROMA15
ROMA0 ROMA16
ROMA17
ROMA18
ROMA19
ROMA20
ROMA2
ROMA21
ROMA22
ROMA3
ROMA23
ROMA4
ROMA5
ROMA1
ROMA6
ROMA7
ROMA8
ROMA9
ROMA10
AS_ROMA0_R
ROMA0
P3V3_STBY P3V3_STBY P3V3_STBY P3V3_STBY
P3V3_STBY
ROMA[23..0]43
ROMD0_R 43
ROMD1_R 43
ROMD2 43
ROMD3 43
ROMD4 43
ROMD5 43
ROMD6 43
ROMD7 43
ROMA0 43
Title 
Size Document Number R e v 
Date: Sheet 
o f 
Honey badger_LSI Base Board 1B
AST1250 STRAPPING
A3
46 71Tuesday, January 20, 2015
Honey badger_LSI Base Board
http://www.wiwynn.com
8F, 90, Sec.1, Xintai 5th Rd., Xizhi Dist.,
New Taipei City 22102, Taiwan (R.O.C.)
Title 
Size Document Number R e v 
Date: Sheet 
o f 
Honey badger_LSI Base Board 1B
AST1250 STRAPPING
A3
46 71Tuesday, January 20, 2015
Honey badger_LSI Base Board
http://www.wiwynn.com
8F, 90, Sec.1, Xintai 5th Rd., Xizhi Dist.,
New Taipei City 22102, Taiwan (R.O.C.)
Title 
Size Document Number R e v 
Date: Sheet 
o f 
Honey badger_LSI Base Board 1B
AST1250 STRAPPING
A3
46 71Tuesday, January 20, 2015
Honey badger_LSI Base Board
http://www.wiwynn.com
8F, 90, Sec.1, Xintai 5th Rd., Xizhi Dist.,
New Taipei City 22102, Taiwan (R.O.C.)
R341 3K3R2F-2-GPNOPOP 1 2
R353 3K3R2F-2-GP1 2
R370 3K3R2F-2-GPNOPOP 1 2
R354 3K3R2F-2-GPNOPOP 1 2
R369 3K3R2F-2-GPNOPOP 1 2
R342 3K3R2F-2-GPNOPOP 1 2
R345 3K3R2F-2-GPNOPOP 1 2
R347 3K3R2F-2-GPNOPOP 1 2
R365 3K3R2F-2-GPNOPOP 1 2
R346 3K3R2F-2-GP1 2
R351 3K3R2F-2-GPNOPOP 1 2
R362 3K3R2F-2-GPNOPOP 1 2
R344 3K3R2F-2-GPNOPOP 1 2
R366 3K3R2F-2-GPNOPOP 1 2
R349 3K3R2F-2-GP1 2
R343 3K3R2F-2-GP1 2
R348 3K3R2F-2-GP1 2
R340 3K3R2F-2-GPNOPOP 1 2
R363 3K3R2F-2-GPNOPOP 1 2 R364 3K3R2F-2-GP1 2
R352 3K3R2F-2-GPNOPOP 1 2
R350 3K3R2F-2-GPNOPOP 1 2
R359 3K3R2F-2-GPNOPOP 1 2 R360 3K3R2F-2-GPNOPOP 1 2
R356 3K3R2F-2-GP1 2 R358 3K3R2F-2-GPNOPOP 1 2
R367 3K3R2F-2-GPNOPOP 1 2 R368 3K3R2F-2-GPNOPOP 1 2
R355 3K3R2F-2-GPNOPOP 1 2
R339
3K3R2F-2-GP
1 2
JP1
FCI-CON2-S-GP
1
2
R361 3K3R2F-2-GPNOPOP 1 2
R357 3K3R2F-2-GPNOPOP 1 2



5
5
4
4
3
3
2
2
1
1
D D
C C
B B
A A
ADC Voltage Divider 
P0V9_E
P5V_STBY
P12V
P1V8_STBY
P1V5_CP3V3_STBY
P0V955_C
P1V5_E
ADC_P0V9_E 41,44
ADC_P5V_STBY 41,44
ADC_12V 41,44
ADC_P1V8_STBY 41,44
ADC_P1V5_C 41,44ADC_P3V3_STBY 41,44
ADC_P0V955_C 41,44
ADC_P1V5_E 41,44
Title 
Size Document Number R e v 
Date: Sheet 
o f 
Honey badger_LSI Base Board 1B
AST1250_VOLTAGE SENSE
A3
47 71Tuesday, January 20, 2015
Honey badger_LSI Base Board
http://www.wiwynn.com
8F, 90, Sec.1, Xintai 5th Rd., Xizhi Dist.,
New Taipei City 22102, Taiwan (R.O.C.)
Title 
Size Document Number R e v 
Date: Sheet 
o f 
Honey badger_LSI Base Board 1B
AST1250_VOLTAGE SENSE
A3
47 71Tuesday, January 20, 2015
Honey badger_LSI Base Board
http://www.wiwynn.com
8F, 90, Sec.1, Xintai 5th Rd., Xizhi Dist.,
New Taipei City 22102, Taiwan (R.O.C.)
Title 
Size Document Number R e v 
Date: Sheet 
o f 
Honey badger_LSI Base Board 1B
AST1250_VOLTAGE SENSE
A3
47 71Tuesday, January 20, 2015
Honey badger_LSI Base Board
http://www.wiwynn.com
8F, 90, Sec.1, Xintai 5th Rd., Xizhi Dist.,
New Taipei City 22102, Taiwan (R.O.C.)
R5771
1KR2F-3-GP
1 2
R5772
1KR2F-3-GP
1 2
C8087
SCD1U25V2KX-2-GP
1 2
C8084
SCD1U25V2KX-2-GP
1 2
R434
3K3R2F-2-GP
12
C8085
SCD1U25V2KX-2-GP
1 2
C8083
SCD1U25V2KX-2-GP
1 2
R5766
1KR2F-3-GP
1 2
R5770
1KR2F-3-GP
1 2
C8086
SCD1U25V2KX-2-GP
1 2
R5763
1KR2F-3-GP
1 2
R5765
1K8R2F-GP
1 2
R3029
1KR2F-3-GP
1 2
R5767
1KR2F-3-GP
NOPOP
1 2
C8089
SCD1U25V2KX-2-GP
1 2
R5769
1KR2F-3-GP
1 2
R3099
1KR2F-3-GP
NOPOP
1 2
R5768
1KR2F-3-GP
1 2
R3098
1KR2F-3-GP
NOPOP
1 2
C8081
SCD1U25V2KX-2-GP
1 2
R5764
5K6R2F-2-GP
1 2
C8088
SCD1U25V2KX-2-GP
1 2
R5762
1KR2F-3-GP
NOPOP
1 2
R3100
1KR2F-3-GP
NOPOP
1 2



5
5
4
4
3
3
2
2
1
1
D D
C C
B B
A A
BCM5221 PHY 
50M_CLK_OE
CLK_50M_BMC0
CLK_50M_RMII_PHY
FM_OSC_50M_EN
NC_PHY_RXC
RMII_BMC_RX_ER_R
RMII_BMC_CRS_DV_R
RMII_PHY_BMC_RXD0_R
PHY_TX_ER_PD
RMII_PHY_BMC_RXD1_R
PHY_AVDD
NC_PHY_TXC
PHY_LNKLED_N
PHY_F100
BMC_PHY_RDAC
BCM5221_RX_C_DN
CLK_50M_RMII_PHY
PHY_FDX
PHY_ANEN
BCM5221_RX_C_DP
PHY_AD4
PHY_AD0
PHY_AD3
PHY_AD1
PHY_TEST_EN
PHY_ACTLED_N
MOD_IMC_FAB_D_COP
BCM5221_RX_C_DP
BCM5221_TX_C_DN
BCM5221_RX_C_DN
BCM5221_TX_C_DP
RMII_BMC_MDIO_R
NC_PHYSPLOED_N
NC_PHY_ENGY_DET
PHY_LOW_PWR
BCM5221_TX_C_DN
BCM5221_MB_RX_DP
BCM5221_MB_TX_DN
BCM5221_MB_RX_DN
BCM5221_MB_TX_DP
MOD_IMC_FAB_D_COP
BCM5221_TX_C_DP
BCM5221_TX_C_DN
BCM5221_TX_C_DP
RMII_BMC_MDC_R
PHY_RESET#
MOD_IMC_FAB_D_COP
PHY_LOW_PWR
BCM5221_RX_C_DP
PHY_FDX
PHY_AD4
PHY_AD1
PHY_ANEN
BCM5221_TX_C_DN
PHY_TX_ER_PD
BCM5221_RX_C_DN
BCM5221_TX_C_DP
PHY_AD3
PHY_F100
PHY_AD0
PHY_DVDD
NC_PHY_BMC_INTR_N
PHY_DVDD
RMII_BMC_MDIO_R
RMII_BMC_MDC_R
50M_CLK_OUT 50M_CLK_OUT_R
CLK_50M_BMC_NCSI
NCSI_10G_RCLK
P3V3_STBYP3V3_STBY
P3V3_STBY
P3V3_STBY
P3V3_STBY P3V3_STBY
P3V3_STBY
P3V3_STBY
P3V3_STBY
P3V3_STBY
PHY_DVDD
P3V3_STBY P3V3_STBY
P3V3_STBY
PHY_AVDD
P3V3_STBY
P3V3_STBY
RMII_PHY_BMC_RXD1 43
RMII_PHY_BMC_RXD0 43
RMII_BMC_PHY_TXD1 43
RMII_BMC_PHY_TXD0 43
RMII_BMC_TX_EN 43
RMII_BMC_RX_ER 43
RMII_BMC_CRS_DV 43
RMII_BMC_MDIO 43
RMII_BMC_MDC 43
BCM5221_MB_RX_DP 49
BCM5221_MB_RX_DN 49
PHY_ACTLED_N49
BCM5221_MB_TX_DP 49
BCM5221_MB_TX_DN 49
PHY_LNKLED_N49
FM_BMC_RESET_N44
CLK_50M_BMC0 43
CLK_50M_BMC_NCSI 43
NCSI_10G_RCLK 40
Title 
Size Document Number R e v 
Date: Sheet 
o f 
Honey badger_LSI Base Board 1B
ETHERNET PHY_BCM5221
A3
48 71Tuesday, January 20, 2015
Honey badger_LSI Base Board
http://www.wiwynn.com
8F, 90, Sec.1, Xintai 5th Rd., Xizhi Dist.,
New Taipei City 22102, Taiwan (R.O.C.)
Title 
Size Document Number R e v 
Date: Sheet 
o f 
Honey badger_LSI Base Board 1B
ETHERNET PHY_BCM5221
A3
48 71Tuesday, January 20, 2015
Honey badger_LSI Base Board
http://www.wiwynn.com
8F, 90, Sec.1, Xintai 5th Rd., Xizhi Dist.,
New Taipei City 22102, Taiwan (R.O.C.)
Title 
Size Document Number R e v 
Date: Sheet 
o f 
Honey badger_LSI Base Board 1B
ETHERNET PHY_BCM5221
A3
48 71Tuesday, January 20, 2015
Honey badger_LSI Base Board
http://www.wiwynn.com
8F, 90, Sec.1, Xintai 5th Rd., Xizhi Dist.,
New Taipei City 22102, Taiwan (R.O.C.)
R528
33R2J-2-GP
1 2
C225
SCD1U16V2KX-3GP 
1 2
R374 
2K2R2J-2-GP 
NOPOP
1 2
R372 0R2J-2-GP1 2
C221
SC1KP50V2KX-1GP 
1 2
C236
SCD1U16V2KX-3GP
1 2
TP132 1
R403
0R2J-2-GP
NOPOP
1 2
R377 33R2J-2-GPNOPOP1 2
R404 
49D9R2F-GP 
NOPOP
12
R385 0R2J-2-GP 12
BC1
SC2D2U10V3KX-1GP 
1 2
TP1291
R455 
4K75R2F-1-GP 
NOPOP
1 2
R379 33R2J-2-GP1 2
R399
10KR2F-2-GP
1 2
R382 
1K27R2D-GP 
1 2
R383 
4K75R2F-1-GP 
1 2
C232
SC1U6D3V3KX-2GP
1 2
TP1301
R378
150R2F-1-GP
1 2
R394 4K75R2F-1-GP 
1 2
C228
SCD1U16V2KX-3GP 
1 2
R396 150R2F-1-GP 
1 2
C222
SCD01U16V2KX-3GP 
1 2
R459 
4K75R2F-1-GP 
1 2
BC2
SC2D2U10V3KX-1GP 
1 2
R380 0R2J-2-GP1 2
C220
SC1KP50V2KX-1GP 
1 2
R406
220R2J-L2-GP
NOPOP
1 2
R391 4K75R2F-1-GP 
1 2
U20
BCM5221A4KMLG-2-GP-U
NOPOP
CRS_DV 1
REGDVDD/OVDD 2
REF_CLK 3
GND 4
NC#5 5
RESET#6
PHYAD0/FDX_LED#7
PHYAD1/COL_LED#8
PHYAD3/PAUSE9
PHYAD410
TESTEN11
LOW_PWR12
ENERGY_DET13
GND 14 
REGAVDD 15 
BIASVDD 16 
RDAC17
RD- 18 RD+ 19 
AVDD 20 
TD- 21 TD+ 22 
RCVLED#/ACTLED#/MDIX_DIS 23 
XMTLED#/INTR#/FDXLED# 24 
LNKLED#/MEDIA_CONVI# 25 
SPDLED#/ADV_PAUSE 26 
F10027
ANEN28
FDX29
MDIO 30
MDC 31
NC#32 32 
NC#33 33 
OVDD 34 
RXD1 35
RXD0 36
NC#37 37 
RXC 38
RXER 39
TXER 40
TXC 41
DVDD 42 
TXEN 43
TXD0 44TXD1 45
NC#46 46 
NC#47 47 
NC#48 48 
GND 49 
C224
SCD01U16V2KX-3GP 
1 2
C229
SCD1U16V2KX-3GP 
1 2
TP128 1
R390 4K75R2F-1-GP 
1 2
R397
49D9R5F-2-GP 
0805
49.9
+-1%
1 2
R405 
49D9R2F-GP 
NOPOP
12
C235
SC27P50V2JN-2DLGP
NOPOP
12
R400
10KR2F-2-GP
1 2
C234
SC27P50V2JN-2DLGP
NOPOP
12
TP131 1
C227
SC10U6D3V5KX-1GP 
1 2
R381 0R2J-2-GP1 2
R395 150R2F-1-GP 
1 2
U21
ICS551MLFT-GP
ICLK1 Q1 2
Q2 3
Q3 4
Q4 5
GND 6VDD 7
OE8
X1
OSC-50MHZ-8-GP-U
CONT1
GND2 OUT 3
VDD 4
R371
10KR2F-2-GP
NOPOP
1 2
R392 4K75R2F-1-GP 
1 2
C231
SCD1U16V2KX-3GP 
1 2
R386 0R2J-2-GP 12
TP1261
C237
SCD1U16V2KX-3GP
NOPOP
1 2
C233
SC1U6D3V3KX-2GP
1 2
R401 
49D9R2F-GP 
12
R387
4K7R2J-2-GP 
NOPOP
1 2
R376 33R2J-2-GP1 2
R398
49D9R5F-2-GP 
0805
49.9
+-1%
1 2
R389 0R2J-2-GP 12
R384 
4K75R2F-1-GP 
1 2
R402 
49D9R2F-GP 
12
C230
SCD1U16V2KX-3GP 
1 2
R388 0R2J-2-GP 12
TP1271
C226
SC10U6D3V5KX-1GP 
NOPOP
1 2
R375 33R2J-2-GP1 2
R393 4K75R2F-1-GP 
1 2
C223
SCD1U16V2KX-3GP 
1 2



5
5
4
4
3
3
2
2
1
1
D D
C C
B B
A A
LED_MDI0_ACT
TP_LAN_4
TP_LAN_5
TP_LAN_6
LED_MDI0_LINK
TP_LAN_7
RJ45_GND_7
RJ45_GND_1
P3V3_STBY
P3V3_STBY
PHY_AVDD
BCM5221_MB_TX_DP48
BCM5221_MB_TX_DN48
BCM5221_MB_RX_DP48
BCM5221_MB_RX_DN48
PHY_ACTLED_N 48
PHY_LNKLED_N 48
Title 
Size Document Number R e v 
Date: Sheet 
o f 
Honey badger_LSI Base Board 1B
 LAN CONNECTOR
A3
49 71Tuesday, January 20, 2015
Honey badger_LSI Base Board
http://www.wiwynn.com
8F, 90, Sec.1, Xintai 5th Rd., Xizhi Dist.,
New Taipei City 22102, Taiwan (R.O.C.)
Title 
Size Document Number R e v 
Date: Sheet 
o f 
Honey badger_LSI Base Board 1B
 LAN CONNECTOR
A3
49 71Tuesday, January 20, 2015
Honey badger_LSI Base Board
http://www.wiwynn.com
8F, 90, Sec.1, Xintai 5th Rd., Xizhi Dist.,
New Taipei City 22102, Taiwan (R.O.C.)
Title 
Size Document Number R e v 
Date: Sheet 
o f 
Honey badger_LSI Base Board 1B
 LAN CONNECTOR
A3
49 71Tuesday, January 20, 2015
Honey badger_LSI Base Board
http://www.wiwynn.com
8F, 90, Sec.1, Xintai 5th Rd., Xizhi Dist.,
New Taipei City 22102, Taiwan (R.O.C.)
R413
0R2J-2-GP
12
R416 0R2J-2-GPNOPOP 12
C325
SCD1U16V2KX-3GP 
1 2
YELLOW 
GREEN 
GREEN 
RJ1
RJ45-LED-12P-10-GP
NOPOP
1
2
3
4
5
6
7
8
9
10
11
12
13
14
D1
D2
D3
D4
D5
NP1
NP2
R418 0R2J-2-GPNOPOP 12
R420
150R3J-L-GP12
R417 0R2J-2-GPNOPOP 12
R414
0R2J-2-GP
12
C324
SCD1U16V2KX-3GP 
1 2
R419 0R2J-2-GPNOPOP 12
R415
150R3J-L-GP12



5
5
4
4
3
3
2
2
1
1
D D
C C
B B
A A
ADD=0101100 (0x58) 
USB HUB 
USB_P1_F_DN1
USB_P1_F_DP1
PLLFILT
CRFILT
CRFILT
PLLFILT
RBIAS
USB_HUB_XTAL_OUT
USB_HUB_XTAL_IN USB_P1_DN
USB_P1_DP
USB_OCS_N1
USB_OCS_N2
USB_OCS_N3
USB_OCS_N4
USB_OCS_N3
USB_OCS_N4
USB_OCS_N2
USB_EN_4
USB_EN_3
USB_EN_2
USB_EN_1
USB_SUSP_IND
USB_SUSP_IND
USB_EN_1
USB_EN_2
USB_EN_3
USB_EN_4
CFG_SEL0
CFG_SEL1
VBUS_DET
VBUS_DET
USB_RESET_N
CFG_SEL0
USB_RESET_N
CFG_SEL1
USB_P0_DP_R
USB_P0_DN_R
USB_P1_DP USB_DP_R
USB_P0_DP
USB_P1_DN USB_DN_R
USB_P0_DN
USB_HUB_XTAL_OUT
USB_OCS_N1
USB_OCS_N1 USB_EN_1
P5V_USB_BP1_F
USB_P1_F_DP1
USB_P1_F_DN1
USB_HUB_XTAL_IN
P5V_USB
P5V_USB
P3V3_STBY
P3V3_STBY
P3V3_STBY P3V3_STBY P3V3_STBY P3V3_STBY P3V3_STBY P3V3_STBY P3V3_STBYP3V3_STBY
P3V3_STBY P3V3_STBYP3V3_STBYP3V3_STBY
AGND_USB
P5V_STBY
P5V_STBY
P5V_USB
AGND_USB
USB_P2_DP 44
USB_P2_DN 44
USB_P4_DP 44
USB_P4_DN 44
USB_P3_DP 44
USB_P3_DN 44
BMC_I2C_D_SDA 41,42
BMC_I2C_D_SCL41,42
USB_P0_DP 33
USB_P0_DN 33
USB_P0_DP33
USB_P0_DN33
PMU_PLTRST_N13,18,31,33,40,42,44,52
USB_OCS_N1 43
Title 
Size Document Number R e v 
Date: Sheet 
o f 
Honey badger_LSI Base Board 1B
USB2.0*1
A3
50 71Tuesday, January 20, 2015
Honey badger_LSI Base Board
http://www.wiwynn.com
8F, 90, Sec.1, Xintai 5th Rd., Xizhi Dist.,
New Taipei City 22102, Taiwan (R.O.C.)
Title 
Size Document Number R e v 
Date: Sheet 
o f 
Honey badger_LSI Base Board 1B
USB2.0*1
A3
50 71Tuesday, January 20, 2015
Honey badger_LSI Base Board
http://www.wiwynn.com
8F, 90, Sec.1, Xintai 5th Rd., Xizhi Dist.,
New Taipei City 22102, Taiwan (R.O.C.)
Title 
Size Document Number R e v 
Date: Sheet 
o f 
Honey badger_LSI Base Board 1B
USB2.0*1
A3
50 71Tuesday, January 20, 2015
Honey badger_LSI Base Board
http://www.wiwynn.com
8F, 90, Sec.1, Xintai 5th Rd., Xizhi Dist.,
New Taipei City 22102, Taiwan (R.O.C.)
R446
0R3J-0-U-GP
1 2
C240
SCD1U16V2JX-1-GP
1 2
R535
4K7R2F-GP
1 2
C158
SC1U10V2KX-4-GP
1 2
C239
SC1KP50V2KX-1GP
1 2
R545
0R3J-0-U-GP
1 2
U194
TPS2065DBVT-GP
OUT1
GND2
OC#3 EN 4
IN 5
R550
4K7R2F-GP
1 2
R216
4K7R2F-GP
1 2
C167
SC1U10V2KX-4-GP
1 2
TC14
SC47U16V0MX-GP 
1 2
C318
SC1U6D3V3KX-2GP
NOPOP
1 2
C155
SC1U10V2KX-4-GP
1 2
R558
0R2J-2-GP
1 2
R217
4K7R2F-GP
1 2
R559
0R3J-0-U-GP
NOPOP
1 2
R551 0R3J-0-U-GP1 2
C336
SC1U10V3KX-4GP-U 
1 2
TC11
SC47U16V0MX-GP 
1 2
R552
4K7R2F-GP
NOPOP
1 2
TP1691
C254
SC1U10V2KX-4-GP
1 2
R7899
4K7R2F-GP
NOPOP
1 2
R549
4K7R2F-GP
NOPOP
1 2
R410 0R2J-2-GP
1 2
C166
SC1U10V2KX-4-GP
1 2
R409 0R2J-2-GP
1 2
R536
0R2J-2-GP
NOPOP 12
C238
SCD1U16V2JX-1-GP
1 2
R407
10KR2F-2-GP
1 2
C159
SC1U10V2KX-4-GP
1 2
R700
12KR2J-L-GP
1 2
C335
SC1U10V3KX-4GP-U 
1 2
SKT1
SKT-USB-250-GP
1
2
3
4
5
6
R223
4K7R2F-GP
1 2
R557 0R3J-0-U-GP1 2
TC10
SC47U16V0MX-GP 
1 2
C8090
SC18P50V3JN-1-GP
1 2
R227
4K7R2F-GP
1 2
R7897
4K7R2F-GP
NOPOP
1 2
R248
4K7R2F-GP
1 2
R555
0R3J-0-U-GP
NOPOP
1 2
C337
SC1U10V3KX-4GP-U 
1 2
C338
SC1U10V3KX-4GP-U 
1 2
R7898
4K7R2F-GP
1 2
L7
BLM21PG300SN-2GP
12
R554
0R3J-0-U-GP
1 2
TC13
SC47U16V0MX-GP 
1 2
R701
1MR2F-GP
1 2
C8091
SC18P50V3JN-1-GP
1 2
TP1671
R7896
4K7R2F-GP
1 2
R548
4K7R2F-GP
NOPOP
1 2C334
SC1U10V3KX-4GP-U 
1 2
R547
4K7R2F-GP
NOPOP
1 2
C317
SC1U6D3V3KX-2GP
1 2
R222
4K7R2F-GP
1 2
TC12
SC47U16V0MX-GP 
1 2
L8
DLW21HN900SQ2LGP-U
NOPOP
1
3
4
2
U183
USB2514B-AEZC-TR-GP
USBDM_DN1/PRT_DIS_M1 1 USBDP_DN1/PRT_DIS_P1 2
USBDM_DN2/PRT_DIS_M2 3 USBDP_DN2/PRT_DIS_P2 4
VDDA33 5
USBDM_DN3/PRT_DIS_M3 6 USBDP_DN3/PRT_DIS_P3 7
USBDM_DN4/PRT_DIS_M4 8 USBDP_DN4/PRT_DIS_P4 9
VDDA33 10TEST11
PRTPWR1/BC_EN1 12 
OCS_N1 13 
CRFILT 14
VDD33 15
PRTPWR2/BC_EN2 16 
OCS_N2 17 
PRTPWR3/BC_EN3 18 
OCS_N3 19 
PRTPWR4/BC_EN4 20 
OCS_N4 21 
SDA/SMBDATA/NON_REM1 22 
VDD33 23
SCL/SMBCLK/CFG_SEL024
HS_IND/CFG_SEL125
RESET#26
VBUS_DET27
SUSP_IND/LOCAL_PWR/NON_REM0 28 
VDDA33 29
USBDM_UP 30USBDP_UP 31
XTALOUT 32 
XTALIN/CLKIN 33 
PLLFILT 34
RBIAS35
VDD33 36
GND37
R228
4K7R2F-GP
1 2
Note:ZZ.09904.07C01 
U22
AZC099-04S-1-GP
I/O11
GND2
I/O23 I/O3 4
VDD 5
I/O4 6
R556
0R3J-0-U-GP
1 2
X11
XTAL-24MHZ-87-GP
4 1
23
C163
SC1U10V2KX-4-GP
1 2
F1
POLYSW-1D5A8V-4-GP
NOPOP
1 2
R553
4K7R2F-GP
NOPOP
1 2
C162
SC1U10V2KX-4-GP
1 2
R408
15KR2F-GP
1 2
C332
SCD1U16V2JX-1-GP
1 2



5
5
4
4
3
3
2
2
1
1
D D
C C
B B
A A
I2C_B BUFFER 
I2C_C BUFFER 
SAS_I2C_C_BUF_SCL
I2C_C_BUF_READY
I2C_B_BUF_READY
SAS_I2C_C_BUF_SDA BMC_I2C_C_SDA
I2C_B_BUFF_EN
BMC_I2C_C_SCL
BMC_I2C_B_SDA
BMC_I2C_C_SDABMC_I2C_C_SCL
SAS_I2C_B_BUF_SCL
BMC_I2C_B_SCL
I2C_C_BUFF_EN
SAS_I2C_B_BUF_SDA
SAS_I2C_C_BUF_SDASAS_I2C_C_BUF_SCL
P3V3_STBY
P3V3_STBY
P3V3_STBY
P3V3_STBY
P3V3_STBY
P3V3_STBY
P3V3_STBY
P3V3_STBY
SAS_I2C_B_BUF_SCL38
BMC_I2C_B_SCL42
SAS_I2C_B_BUF_SDA 38
BMC_I2C_B_SDA 42
BMC_I2C_C_SCL22,42
SAS_I2C_C_BUF_SCL38
BMC_I2C_C_SDA 22,42
SAS_I2C_C_BUF_SDA 38
Title 
Size Document Number R e v 
Date: Sheet 
o f 
Honey badger_LSI Base Board 1B
I2C LEVEL SHIFT AND BUFFER
A3
51 71Tuesday, January 20, 2015
Honey badger_LSI Base Board
http://www.wiwynn.com
8F, 90, Sec.1, Xintai 5th Rd., Xizhi Dist.,
New Taipei City 22102, Taiwan (R.O.C.)
Title 
Size Document Number R e v 
Date: Sheet 
o f 
Honey badger_LSI Base Board 1B
I2C LEVEL SHIFT AND BUFFER
A3
51 71Tuesday, January 20, 2015
Honey badger_LSI Base Board
http://www.wiwynn.com
8F, 90, Sec.1, Xintai 5th Rd., Xizhi Dist.,
New Taipei City 22102, Taiwan (R.O.C.)
Title 
Size Document Number R e v 
Date: Sheet 
o f 
Honey badger_LSI Base Board 1B
I2C LEVEL SHIFT AND BUFFER
A3
51 71Tuesday, January 20, 2015
Honey badger_LSI Base Board
http://www.wiwynn.com
8F, 90, Sec.1, Xintai 5th Rd., Xizhi Dist.,
New Taipei City 22102, Taiwan (R.O.C.)
R426
10KR2F-2-GP
1 2
U23
PCA9511ADP-T-GP
ENABLE1
SCLOUT2
SCLIN3
GND4 READY 5SDAIN 6SDAOUT 7VCC 8
U24
PCA9511ADP-T-GP
ENABLE1
SCLOUT2
SCLIN3
GND4 READY 5SDAIN 6SDAOUT 7VCC 8
C247 
SC220P50V3JN-GP 
NOPOP 
1 2
C241 
SCD1U16V2KX-3GP 
1 2
R432
0R2J-2-GP
NOPOP1 2
C245 
SC220P50V3JN-GP 
NOPOP 
1 2R423 
4K7R2J-2-GP 
NOPOP 
1 2
C246 
SC220P50V3JN-GP 
NOPOP 
1 2
R431
0R2J-2-GP
NOPOP1 2
R427
2KR2F-3-GP
NOPOP
1 2
C244 
SCD01U50V2KX-1GP 
1 2
R424 
10KR2F-2-GP 
1 2
R429
2KR2F-3-GP
NOPOP
1 2
R430
10KR2F-2-GP
1 2
C242 
SCD01U50V2KX-1GP 
1 2
R428
10KR2F-2-GP
1 2
C243 
SCD1U16V2KX-3GP 
1 2
C248 
SC220P50V3JN-GP 
NOPOP 
1 2R425 
4K7R2J-2-GP 
NOPOP 
1 2



5
5
4
4
3
3
2
2
1
1
D D
C C
B B
A A
Debug Port 
BMC_UART_SWITCH[1:2] 
0     0 
1     1 
1     0 
UART H L
CPU 
EXP_SMART 
IOC 
1~2:CPU 
2~3:EXP 
LED ON:EXP 
CPU UART ISOLATION 
0     1 BMC 
YELLOW LED 
YELLOW LED 
TO DEBUG PORT 
TO BMC 
UART2_RX
UART2_TX
DEBUG_CARD_TX DEBUG_CARD_RX
UART2_TX
UART COUNT
UART2_RX
UART1_TX
BMC_UART_SWITCH_1R 
CPU_UART_TX_R
UART1_RX
CPU_S_TXD
CPU_S_RXD
DEBUG_CARD_RX
DEBUG_CARD_TX
UART1_TX
UART1_RX
BMC_UART_SWITCH_R
CPU_UART_RX_R
DEBUG_LED_SW_H
DEBUG_PORT_GND
DEBUG_LED_SW
LED_SL_SW_ON
EXP_UART_TX_R
EXP_UART_RX_R
UART COUNT
DP_RST_N
CPU_U192_PIN2_TX
CPU_U192_PIN3_RX CPU_U192_PIN6_TX
CPU_U192_PIN5_RX
CPU_S_TXD
CPU_S_RXD
DEBUG_OE_1_N
DEBUG_OE_1_N
DEBUG_OE_1_N
DEBUG_OE_1_N
DEBUG_OE_2_NCPU_U193_PIN2_TX
CPU_U193_PIN3_RX CPU_U193_PIN6_RX
CPU_U193_PIN5_TX
DEBUG_OE_2_N
BMC_CONSOLE_LED0_RBMC_UART_SWITCH_1
CONSOLE_LED_0DEBUG CONSOLE_LED_0
BMC_CONSOLE_LED1_RBMC_UART_SWITCH_2
CONSOLE_LED_1DEBUG CONSOLE_LED_1
DEBUG_OE_2_N
PMU_PLTRST_N
CPU_U192_PIN5_RX
CPU_RXD_R
CPU_U192_PIN3_RX
CPU_U193_PIN3_RX
CPU_U192_PIN3_RX_R
CPU_U193_PIN3_RX_R
P3V3_STBY
P3V3_STBY
P3V3_STBY
P5V_STBY
P3V3_STBY P3V3_STBY
P3V3_STBY
P3V3_STBY
P3V3_STBYP3V3_STBY
P3V3_STBY
P3V3_STBY
P3V3_STBY
P3V3_STBY
P3V3_STBY
P3V3_STBY
P3V3_STBY
P3V3_STBY
P3V3_STBY
BMC_UART_SWITCH_244
DP_RST_N44
LOW_HEX_1 44LOW_HEX_044
LOW_HEX_3 44LOW_HEX_244
HIGH_HEX_044 HIGH_HEX_1 44
HIGH_HEX_244 HIGH_HEX_3 44
BMC_UART_SWITCH_144
UART COUNT 44
DEBUG_LED_SW 44
BMC_TXD5 43
BMC_RXD5 43
EXP_SMART_TX 29
EXP_SMART_RX 29
IOC_UART_RX 18
IOC_UART_TX 18
CPU_TXD33
BMC_DEBUG_OE_1_N44
CPU_TXD33
CPU_BMC_UART_RX 43
CPU_BMC_UART_TX 43
BMC_DEBUG_OE_2_N44
PMU_PLTRST_N13,18,31,33,40,42,44,50
CPU_RXD33
Title 
Size Document Number Rev 
Date: Sheet o f 
Honey badger_LSI Base Board 1B
DEBUG PORT
A2
52 71Tuesday, January 20, 2015
Honey badger_LSI Base Board
http://www.wiwynn.com
8F, 90, Sec.1, Xintai 5th Rd., Xizhi Dist.,
New Taipei City 22102, Taiwan (R.O.C.)
Title 
Size Document Number Rev 
Date: Sheet o f 
Honey badger_LSI Base Board 1B
DEBUG PORT
A2
52 71Tuesday, January 20, 2015
Honey badger_LSI Base Board
http://www.wiwynn.com
8F, 90, Sec.1, Xintai 5th Rd., Xizhi Dist.,
New Taipei City 22102, Taiwan (R.O.C.)
Title 
Size Document Number Rev 
Date: Sheet o f 
Honey badger_LSI Base Board 1B
DEBUG PORT
A2
52 71Tuesday, January 20, 2015
Honey badger_LSI Base Board
http://www.wiwynn.com
8F, 90, Sec.1, Xintai 5th Rd., Xizhi Dist.,
New Taipei City 22102, Taiwan (R.O.C.)
R531
220R2F-GP
12
U46
SN74LVC1G08DCKR-GP
B 2
A 1
GND 3Y4
VCC5
R412 0R2J-2-GP 12
R277 0R2J-2-GP 12
R85
150R2F-1-GP
1 2
SC1303 
SCD1U16V2KX-3GP 
1 2
CN3
JWT-CONN14A-1-GP
1
3
5
7
9
4
6
8
10
2
11 12
13 14
R173 
4K7R2F-GP 
1 2
C330 
SCD1U25V2KX-2-GP 
1 2
R458
33R2J-2-GP
12
Q19
2N7002A-7-GP
G
SD
R487
0R2J-2-GP
1 2
R174 
4K7R2F-GP 
1 2
R647 4K7R2F-GP
1 2
R274
0R2J-2-GP
NOPOP
1 2
R7904
0R2J-2-GP
12
LED14
LED-Y-11-GP
1 2
U192
74HC2G125DP-GP
1OE#1
1A2
2Y3
GND4 2A 51Y 62OE# 7VCC 8
R312 0R2J-2-GP 12
R7903 0R2J-2-GP 12
R454
0R2J-2-GP
1 2
SC1311 
SCD1U16V2KX-3GP 
1 2
R289
10KR2F-2-GP
NOPOP
1 2
R278
0R2J-2-GP
NOPOP
1 2
R433
1KR2F-3-GP
1 2
R7902 0R2J-2-GP 12
R276
10KR2F-2-GP
NOPOP
1 2
R9025
4K7R3F-GP
1 2
Q20
2N7002A-7-GP
G
SD
C4 
SCD1U16V2KX-3GP 
1 2
R7907 0R2J-2-GP 12
SW20
SW-SLIDE74-GP
1
2
3
NP1
NP2
R435 0R2J-2-GP 12
R275 0R2J-2-GP 12
R323 0R2J-2-GP 12
U193
74HC2G125DP-GP
1OE#1
1A2
2Y3
GND4 2A 51Y 62OE# 7VCC 8
U44
SN74LVC1G00DC-1GP
A1
B2
GND3 Y 4
VCC 5
C5
SCD1U16V2KX-3GP
1 2
C319
SCD1U16V2KX-3GP
1 2
U28
TS5A23157DGSR-GP
IN11
NO1 2
GND 3
NO2 4IN25
COM26
NC2 7V+8 NC1 9
COM110
C340
SCD1U25V2KX-2-GP
1 2
LED15
LED-Y-11-GP
1 2
C322
SCD1U16V2KX-3GP
1 2
R657 4K7R2F-GP
1 2
R86
150R2F-1-GP
1 2
LED6
LED-R-46-GP
A K
R7900
0R2J-2-GP
12
R7905 0R2J-2-GP 12
R7906 0R2J-2-GP 12
U42
SN74LVC1G00DC-1GP
NOPOP
A1
B2
GND3 Y 4
VCC 5
U27
TS5A23157DGSR-GP
IN11
NO1 2
GND 3
NO2 4IN25
COM26
NC2 7V+8 NC1 9
COM110
C3 
SCD1U16V2KX-3GP 
1 2
PQ7
2N7002A-7-GP
G
SD
R7901
0R2J-2-GP
12
C249
SCD1U16V2KX-3GP
1 2
R638 4K7R2F-GP
1 2
U26
TS5A23157DGSR-GP
IN11
NO1 2
GND 3
NO2 4IN25
COM26
NC2 7V+8 NC1 9
COM110
C331 
SCD1U25V2KX-2-GP 
1 2
R7908 0R2J-2-GP 12



5
5
4
4
3
3
2
2
1
1
D D
C C
B B
A A
SHUTDOWN LATCH RELEASE 
Red Power Button 
SYSTEM Reset Button 
TO BMC 
TO BMC 
FROM BMC 
SHUTDOWN_RELEASE
FP_PWRBTN_RC_N FP_PWRBTN_R PWRBTN_FP_NFP_PWRBTNFP_PWR_BTN_N
PWRBTN_OUT_N
FP_RESET_RC_N FP_RETBTN_R RSTBTN_FP_NFP_RETBTNCPU_EXP_RST
CPU_EXP_RESET_N
FP_PWR_BTN_N
DP_BMC_CPU_RST_N_U177_OUT
OE_BMC_RSET
RSTBTN_OUT_N
P3V3_STBY
P3V3_STBY P3V3_STBY
P3V3_STBY
P3V3_STBY
P3V3_STBY
P3V3_STBY
P3V3_STBY P3V3_STBY
P3V3_STBY
P3V3_STBY
P3V3_STBY
P3V3_STBY
P3V3_STBY
P3V3_STBY
P3V3_STBY
P3V3_STBY P3V3_STBY
P3V3_STBY
P3V3_STBY
P3V3_STBY
P3V3_STBY
P3V3_STBY
SHUTDOWN_RELEASE38
FM_BMC_READY_N42
BMC_PWRBTN_N42
PMU_PWRBTN_N 33
SYS_PWRBTN_N42
FM_BMC_READY_N42
BMC_RSTBTN_N42
SYS_RSTBTN_N42
CPU_EXP_RESET_N 25
DP_BMC_CPU_RST_N44
CPU_RESET_N 33
BMC_EN_CPU_RESET_CONTROL44
Title 
Size Document Number Rev 
Date: Sheet o f 
Honey badger_LSI Base Board 1B
POWER/RESET_BUTTON
A2
53 71Tuesday, January 20, 2015
Honey badger_LSI Base Board
http://www.wiwynn.com
8F, 90, Sec.1, Xintai 5th Rd., Xizhi Dist.,
New Taipei City 22102, Taiwan (R.O.C.)
Title 
Size Document Number Rev 
Date: Sheet o f 
Honey badger_LSI Base Board 1B
POWER/RESET_BUTTON
A2
53 71Tuesday, January 20, 2015
Honey badger_LSI Base Board
http://www.wiwynn.com
8F, 90, Sec.1, Xintai 5th Rd., Xizhi Dist.,
New Taipei City 22102, Taiwan (R.O.C.)
Title 
Size Document Number Rev 
Date: Sheet o f 
Honey badger_LSI Base Board 1B
POWER/RESET_BUTTON
A2
53 71Tuesday, January 20, 2015
Honey badger_LSI Base Board
http://www.wiwynn.com
8F, 90, Sec.1, Xintai 5th Rd., Xizhi Dist.,
New Taipei City 22102, Taiwan (R.O.C.)
R443
10KR2F-2-GP
1 2
SW2
SW-TACT-4P-196-GP
1 2
3 4
R325
4K7R2F-GP
1 2
R1585
4K7R2F-GP
NOPOP
1 2
R326
4K7R2F-GP
1 2
R1581
33R2F-3-GP
1 2
U175A
TSLVC14APW-2-GP
1 2
14 7
C43 
SCD1U16V2KX-3GP 
1 2
U172
SN74LVC1G08DCKR-GP
B2
A1
GND3 Y 4
VCC 5
R2054
4K7R2F-GP
1 2
R221
10KR2F-2-GP
1 2
C42 
SCD1U16V2KX-3GP 
1 2
R686
0R2J-2-GP
12
R1584
10KR2F-2-GP
1 2
U176
SNLVC1G126DCKR-GP
NOPOP
OE1
A2
GND3 Y 4
VCC 5
U177
SN74LVC1G08DCKR-GP
B2
A1
GND3 Y 4
VCC 5
U174
SNLVC1G126DCKR-GP
OE1
A2
GND3 Y 4
VCC 5
R1580
33R2F-3-GP
1 2
SW1
SW-TACT-4P-185-GP
1 2
3 4 U175B
TSLVC14APW-2-GP
3 4
14 7
R1587 0R2J-2-GP1 2
C82 
SCD1U16V2KX-3GP 
1 2U175C
TSLVC14APW-2-GP
5 6
14 7
U173
SN74LVC1G08DCKR-GP
B2
A1
GND3 Y 4
VCC 5
R473
22KR2F-GP
1 2
U171
SNLVC1G126DCKR-GP
OE1
A2
GND3 Y 4
VCC 5
R2055
4K7R2F-GP
1 2
C371
SC1U6D3V3KX-2GP
1 2
R219
10KR2F-2-GP
1 2
C41 
SCD1U16V2KX-3GP 
1 2
C83 
SCD1U16V2KX-3GP 
1 2
C370
SC1U6D3V3KX-2GP
1 2 R1578
10KR2F-2-GP
1 2
C255
SC1U6D3V3KX-2GP
1 2
SW3
PUSH-SW132-GP
1
2
3
4
5
NP1 NP2 
R453
8K2R2J-3-GP
1 2
R685 0R2J-2-GP 12
U175D
TSLVC14APW-2-GP
9 8
14 7
R1583 0R2J-2-GP1 2
R1586
33R2F-3-GP
1 2
R1582
33R2F-3-GP
1 2
C316
SC1U16V3KX-5GP
1 2
C81 
SCD1U16V2KX-3GP 
1 2
R1579
4K7R2F-GP
NOPOP
1 2



5
5
4
4
3
3
2
2
1
1
D D
C C
B B
A A
Slave address: 0xFC 
I2C Address = 0xFC 
V(on)=1.3V 
P12V_STBY HSC 
VR_HSC_GATE_MSB
HS_ADR
VR_HSC_TIMER_MSB
VR_HSC_GATE_R_MSB
VSENSE_HSC_MSB
HSC_MSB_ALERT_N
HSW_SCL1
HSW_SDA1
PRSNT_EN_HPIC
HSC_MSB_ALERT_N
MSB_PRSNT_AND_3PRSNT_AND_2
PRSNT_EN_HPIC
P12V_PCIE
P12V_PCIE
P12V_MSB
P12V_PCIE
P12V_MSB
P3V3_STBY
P3V3_STBY P3V3_STBY
HSC_MSB_ALERT_N 44
BMC_I2C_SDA_10 37,41,42,55
BMC_I2C_SCL_10 37,41,42,55
BMC_I2C_A_SDA 39,41,42,55
BMC_I2C_A_SCL 39,41,42,55
P0V9_E_PG 39,41,42,55PRSNT_CONTROL_BMC44
PRSNT_MSB_AND_140
Title 
Size Document Number R e v 
Date: Sheet 
o f 
Honey badger_LSI Base Board 1B
12V-DCIN_SERVER BOARD
A3
54 71Tuesday, January 20, 2015
Honey badger_LSI Base Board
http://www.wiwynn.com
8F, 90, Sec.1, Xintai 5th Rd., Xizhi Dist.,
New Taipei City 22102, Taiwan (R.O.C.)
Title 
Size Document Number R e v 
Date: Sheet 
o f 
Honey badger_LSI Base Board 1B
12V-DCIN_SERVER BOARD
A3
54 71Tuesday, January 20, 2015
Honey badger_LSI Base Board
http://www.wiwynn.com
8F, 90, Sec.1, Xintai 5th Rd., Xizhi Dist.,
New Taipei City 22102, Taiwan (R.O.C.)
Title 
Size Document Number R e v 
Date: Sheet 
o f 
Honey badger_LSI Base Board 1B
12V-DCIN_SERVER BOARD
A3
54 71Tuesday, January 20, 2015
Honey badger_LSI Base Board
http://www.wiwynn.com
8F, 90, Sec.1, Xintai 5th Rd., Xizhi Dist.,
New Taipei City 22102, Taiwan (R.O.C.)
C266
SC2200P50V2KX-2GP
1 2
PR6888
5K36R2F-GP
1 2
C311 
SC1U25V3KX-GP 
1 2
C265
SCD047U16V2KX-1-GP
1 2
R45
0R2J-2-GP
NOPOP
1 2
R522
10R2F-L-GP
1 2
R488 
4K7R2F-GP 
1 2
C271 
SCD1U25V2KX-2-GP 
1 2
R520
D008R2512F-GP
1 2
R490 
4K7R2F-GP 
1 2
C267
SCD1U25V3KX-GP
1 2
PR6889
2K05R2F-GP
1 2
D
S
G
Q76
PSMN0R9-25YLC-GP5
4
1
2
3
U45
SN74LVC1G11DCKR-GP
A1
GND2
B3 Y 4VCC 5C 6
PR90010R2J-2-GP 1 2
C274
SCD1U25V3KX-GP
1 2
R527
1K33R3F-GP
1 2
C310 
SCD1U25V2KX-2-GP 
1 2
C309 
SCD1U25V2KX-2-GP 
1 2
PR90000R2J-2-GP 1 2
C268
SC22U6D3V5MX-2GP 
NOPOP1 2
R22
10KR2F-2-GP
12
PR90030R2J-2-GP NOPOP1 2
C312
SCD1U25V3KX-GP
1 2
U34
ADM1178-2ARMZ-R7-GP
VCC1 SENSE 2
ON3
GND4 TIMER5 SCL 6
SDA 7
ADR8 GATE 9
ALERT# 10
PR90020R2J-2-GP NOPOP1 2
C308
SC22U25V5MX-GP 
1 2



5
5
4
4
3
3
2
2
1
1
D D
C C
B B
A A
1.4V 
MB0_P12V_PWGIN_R
MB0_TIME_R
MB0_CM_GATE_R
MB0_CM_ADR1_R
MB0_TEMP
MB0_P12V_PWRGOOD
MB0_SPISS_PD
MB0_CM_OV_R
MB0_CM_SENSE_R1_P
MB0_PSET_R
MB0_P12V_PWRGOOD
MB0_VCAP_R MB0_ISET_R
MB0_SPISS_PD
MB0_CM_ADR2_R
MB0_CM_SENSE_R1_N
MB0_CM_VOUT_R
MB0_CM_GATE
MB0_12V_CTRL_GATE1 
MB0_CM_UV_R
MB0_ISTART_R
MB0_CM_GATE
MB0_VCAP_R
MB0_P12V_R
MB0_CM_ADR1_R MB0_CM_ADR2_R
MB0_VCAP_R
MB0_CM_SENSE_R1_N
MB0_CM_SENSE_P MB0_CM_SENSE_R1_P
MB0_CM_SENSE_N
MB0_P12V_PWGIN_R
MB0_TEMP
MB0_RETRY_R
MATED_P12V_ENMB0_HS_ENABLE
HSW_SCL_2
HSW_SDA_2
MB0_P12V_MAIN_R
P12V_PCIE
MB0_TIME_R
MB0_ISET_R
MB0_PSET_R
MB0_CM_SENSE_P
MB0_CM_SENSE_N
MB0_CM_VOUT_R
MB0_VCC
MB0_VCAP_R
MB0_CM_OV_R
MB0_ISTART_R
MB0_CM_UV_R
MB0_RETRY_R
P12V_PCIE
P12V
MB0_P12V_MAIN_R
AGND_CURRENT_MON 
AGND_CURRENT_MON
AGND_CURRENT_MON
AGND_CURRENT_MON
AGND_CURRENT_MON
AGND_CURRENT_MON
AGND_CURRENT_MON
AGND_CURRENT_MON
AGND_CURRENT_MON
AGND_CURRENT_MON
P12V
AGND_CURRENT_MON
AGND_CURRENT_MON
AGND_CURRENT_MON
AGND_CURRENT_MON
AGND_CURRENT_MON AGND_CURRENT_MON
P12V
AGND_CURRENT_MON
P12V_PCIE
P12V_PCIE
AGND_CURRENT_MON
AGND_CURRENT_MON 
PCIe_MATED#_B 38 PCIe_MATED#_A 38
BMC_I2C_SDA_10 37,41,42,54
BMC_I2C_A_SDA 39,41,42,54
BMC_I2C_SCL_10 37,41,42,54
BMC_I2C_A_SCL 39,41,42,54
MB0_P12V_PWRGOOD56
Title 
Size 
Document Number R ev 
Date: Sheet o f 
Honey badger_LSI Base Board 1B
12V-DCIN_ADM1278 HSC
C
55 71Tuesday, January 20, 2015
Honey badger_LSI Base Board
http://www.wiwynn.com
8F, 90, Sec.1, Xintai 5th Rd., Xizhi Dist.,
New Taipei City 22102, Taiwan (R.O.C.)
Title 
Size 
Document Number R ev 
Date: Sheet o f 
Honey badger_LSI Base Board 1B
12V-DCIN_ADM1278 HSC
C
55 71Tuesday, January 20, 2015
Honey badger_LSI Base Board
http://www.wiwynn.com
8F, 90, Sec.1, Xintai 5th Rd., Xizhi Dist.,
New Taipei City 22102, Taiwan (R.O.C.)
Title 
Size 
Document Number R ev 
Date: Sheet o f 
Honey badger_LSI Base Board 1B
12V-DCIN_ADM1278 HSC
C
55 71Tuesday, January 20, 2015
Honey badger_LSI Base Board
http://www.wiwynn.com
8F, 90, Sec.1, Xintai 5th Rd., Xizhi Dist.,
New Taipei City 22102, Taiwan (R.O.C.)
U2
ADM1278-2ACPZ-RL-1-GP
VCAP2 MCLK 10MDAT 11
GPO2/ALERT2#14
VOUT20
GND 22
PGND 23
VCC30
UV31
OV32
GND 33
ISTART4
TIMER5
RETRY#17
MO-26
MO+29
HS-27
HS+28
GPO1/ALERT1#/CONV13
PSET1
ISET3
ADR1 7
ADR2 8
SCL 16
SDA 15
GATE 24
TEMP 25
FAULT# 6
SPISS# 9
ENABLE 12
CSOUT 19PWGIN 21
PWRGD 18
C7274
SCD1U25V3KX-GP 
1 2
R2102
26K1R2F-2-GP
1 2
R6910R2J-2-GP 12
R688
10KR2J-3-GP
NOPOP
12
R1226
11KR2F-L-GP
1 2
PR90040R2J-2-GP 1 2
R2110 1KR2J-1-GP
1 2
C7317
SCD1U25V3JX-GP
1 2
R2099
39K2R2F-L-GP
1 2
PQ33
NST3904F3T5G-GP-U
C
B
E
CA1
SC2D2U25V5KX-2-GP 
NOPOP
1 2
D
S
G
Q23
PSMN0R9-25YLC-GP
5
4
1
2
3
R2106
49K9R2F-L-GP
1 2
C372
SCD015U25V2KX-GP
1 2
PR90050R2J-2-GP NOPOP1 2
R2103
150KR2J-GP
1 2
R2115
0R2J-2-GP
NOPOP
1 2
R2117
100KR2J-4-GP
1 2
PC1083
SC1U25V3KX-1-GP
1 2
R2114
0R2J-2-GP
1 2
C7276
SC1U16V3KX-5GP 
1 2
P2121
0R0603-PAD-2-GP-U
1 2
C339
SC22U6D3V5MX-2GP 
1 2
R9021
42K2R2F-L-GP
1 2
PR90060R2J-2-GP 1 2
C7272
SCD1U16V2KX-3GP
12
C7278
SCD1U25V3JX-GP
1 2
R9023
57K6R2F-GP
1 2
R2174
100KR2J-4-GP
1 2
R690
10KR3F-L-GP
1 2
D36
MM3Z15VT1G-GP-U
NOPOP
K A
R692
1K33R3F-GP
1 2
R2172
0R2J-2-GP
1 2
PR90070R2J-2-GP NOPOP1 2
R2113
0R2J-2-GP
NOPOP
1 2
R2118
1MR3J-L-GP
NOPOP
1 2
R2119 10R2F-L-GP 12
R2098
10R2F-L-GP
1 2
R2108
3K74R2F-GP 
1 2
R9020
D002RL3115F-L-GP
12
34
C7316
SCD1U25V3JX-GP
1 2
C7273
SCD01U16V2KX-3GP
1 2
Q93
2N7002A-7-GP
G
SD
R2171
100KR2J-4-GP
1 2
R2111 
10R2J-2-GP 
1 2
R2107
49K9R2F-L-GP
1 2
C7279
SCD033U50V3KX-1GP 
1 2
R2109
6K04R2F-GP 
1 2
Q94
2N7002A-7-GP
G
SD
D37
SMF15A-GP
AK
C7277 
SC1U16V3KX-5GP 
1 2
R2122 10R2F-L-GP 12
R1227
100KR2F-L1-GP
1 2
C7275
SC1U16V3KX-5GP 
1 2
R9022
86K6R2F-GP
1 2



5
5
4
4
3
3
2
2
1
1
D D
C C
B B
A A
Power rail :P5V_STBY 
Controller : TPS53312 (Fswitching=700KHz) 
TDC :2.0A 
MAX :2.0A 
OCP :4.1A 
FS=700KHz 
SS=1.4ms 
P5V_STBY_VRG5
P5V_STBY__SNB
P5V_STBY_VIN
P5V_STBY_CC
P5V_STBY_VBST_RR
P5V_STBY_OUT
P5V_STBY_EN_R
P5V_STBY_VO
P5V_STBY_VFB
P5V_STBY_SS
P5V_STBY_VBST
P5V_STBY_VFB
P5V_STBY_CC 
P5V_STBY_VIN
P5V_STBY_VFB_R
P5V_STBY_CC_R
P5V_STBY_VCC
P5V_STBY_SW
P12V
AGND_P5V_STBY
AGND_P5V_STBY
AGND_P5V_STBY
P12V
AGND_P5V_STBY 
P5V_STBY
P5V_STBY_PG57
MB0_P12V_PWRGOOD55
Title 
Size Document Number R e v 
Date: Sheet 
o f 
Honey badger_LSI Base Board 1B
PWRSW_P5V_STBY_TPS53312
A3
56 71Tuesday, January 20, 2015
Honey badger_LSI Base Board
http://www.wiwynn.com
8F, 90, Sec.1, Xintai 5th Rd., Xizhi Dist.,
New Taipei City 22102, Taiwan (R.O.C.)
Title 
Size Document Number R e v 
Date: Sheet 
o f 
Honey badger_LSI Base Board 1B
PWRSW_P5V_STBY_TPS53312
A3
56 71Tuesday, January 20, 2015
Honey badger_LSI Base Board
http://www.wiwynn.com
8F, 90, Sec.1, Xintai 5th Rd., Xizhi Dist.,
New Taipei City 22102, Taiwan (R.O.C.)
Title 
Size Document Number R e v 
Date: Sheet 
o f 
Honey badger_LSI Base Board 1B
PWRSW_P5V_STBY_TPS53312
A3
56 71Tuesday, January 20, 2015
Honey badger_LSI Base Board
http://www.wiwynn.com
8F, 90, Sec.1, Xintai 5th Rd., Xizhi Dist.,
New Taipei City 22102, Taiwan (R.O.C.)
PL1
COIL-6D8UH-10-GP
1 2
PR5
0R6J-3-GP
1 2
PC17
SC47U10V6MX-GP 
1 2
PR4
2D2R3J-2-GP
1 2
PC16
SC22U10V5MX-GP 
1 2
PR15
3D01R5F-GP
NOPOP
1 2
PR13
10KR2F-2-GP
12
PC7
SC22U25V5MX-GP 
1 2
PC18
SC47U10V6MX-GP 
1 2
PR14
2KR2F-3-GP 
NOPOP1 2
PC11
SC3300P50V2KX-1GP
1 2
PC15
SC22U10V5MX-GP 
1 2
PC13
SC1U16V3KX-5GP
1 2
PC20
SC1U10V2KX-1GP
12
PC6
SCD1U25V3KX-GP 
1 2
PC8
SC22U25V5MX-GP 
1 2
PR22
0R2J-2-GP
12
PC10
SCD1U50V3KX-GP
12
PC14
SCD1U50V3KX-GP 
NOPOP
12
PR17
2K05R2F-GP
NOPOP
1 2
PR12
0R2J-2-GP
12
PG1
GAP-CLOSE-PWR-4-GP 
1 2
PR9
10R3F-GP
1 2
PC12
SC2K2P50V3KX-GP
NOPOP
1 2
PG2
COPPER-CLOSE-GP-U
1 2
PC5
SC1U25V3KX-GP 
1 2 PU1
TPS53312RGTR-GP
VBST 12
VIN#13 13
SW#9 9
VREG52
PG5
GND4
SS3
VFB1
VO16
VCC15
EN6 SW#10 10
SW#11 11
VIN#14 14
PGND 7
PGND 8GND17
PC19
SC1KP50V2KX-1GP 
NOPOP
1 2
PC9 SC1U10V2KX-1GP
NOPOP
1 2
PR6 10KR2F-2-GP1 2
PR16
5K36R2F-GP
NOPOP
1 2
PR11 0R2J-2-GP 12
PR10 54K9R2F-L-GP1 2



5
5
4
4
3
3
2
2
1
1
D D
C C
B B
A A
FCCM Mode SS=5.6ms 
OCP = 8.5A 
Power rail : P3V3_STBY(3.3V) 
Controller : TPS53318 (Fswitching=500KHz) 
TDC : 3.9A 
MAX : 3.9A 
OCP : 7A 
FS=500KHz 
P3V3_STBYP3V3_STBY_ROVP
P3V3_STBY_VIN
P3V3_STBY_VREG
P3V3_STBY_LL
P3V3_STBY_EN
P3V3_STBY_RF
P3V3_STBY_VREG
P3V3_STBY_TRIP
P3V3_STBY_VBST 
P3V3_STBY_MODE
P3V3_STBY_OUT
P3V3_STBY_VBST_RC
P3V3_STBY_VDD
P3V3_STBY_SNB
P3V3_STBY_VFB_R 
P3V3_STBY_LL_R
P3V3_STBY_VFB
P3V3_STBY
P3V3_STBY_OUT
P12V
AGND_P3V3_STBY
AGND_P3V3_STBY
AGND_P3V3_STBY
AGND_P3V3_STBY
P12V
AGND_P3V3_STBY
P5V_STBY
AGND_P3V3_STBY
P3V3_STBY_VREG
P3V3_STBY_PG37,58
P5V_STBY_PG56
Title 
Size Document Number R e v 
Date: Sheet 
o f 
Honey badger_LSI Base Board 1B
PWRSW_P3V3_STBY_TPS53318
A3
57 71Tuesday, January 20, 2015
Honey badger_LSI Base Board
http://www.wiwynn.com
8F, 90, Sec.1, Xintai 5th Rd., Xizhi Dist.,
New Taipei City 22102, Taiwan (R.O.C.)
Title 
Size Document Number R e v 
Date: Sheet 
o f 
Honey badger_LSI Base Board 1B
PWRSW_P3V3_STBY_TPS53318
A3
57 71Tuesday, January 20, 2015
Honey badger_LSI Base Board
http://www.wiwynn.com
8F, 90, Sec.1, Xintai 5th Rd., Xizhi Dist.,
New Taipei City 22102, Taiwan (R.O.C.)
Title 
Size Document Number R e v 
Date: Sheet 
o f 
Honey badger_LSI Base Board 1B
PWRSW_P3V3_STBY_TPS53318
A3
57 71Tuesday, January 20, 2015
Honey badger_LSI Base Board
http://www.wiwynn.com
8F, 90, Sec.1, Xintai 5th Rd., Xizhi Dist.,
New Taipei City 22102, Taiwan (R.O.C.)
PR20
3D01R5F-GP
1 2
PC31
SC1KP50V2KX-1GP
1 2
PR34 0R2J-2-GP
NOPOP
1 2
PC25
SCD1U25V3KX-GP 
1 2
PC35
SCD1U16V3KX-3GP 
0603
X7R
1 2
PR28
3D01R5F-GP
NOPOP
1 2
PC29 SC1U10V3KX-4GP-U
1 2
PR18
1K4R2F-1-GP
NOPOP
1 2
PR31 73K2R2F-GP1 2
PC38
SC100U6D3V6MX-GP 
1206
X5R
1 2
PC23
SC22U25V5MX-GP 
1 2
PC40
SC100U6D3V6MX-GP 
1206
X5R
1 2
PR27
10R3F-GP
1 2
PR33 44K2R2F-1-GP1 2
PC21
SC22U25V5MX-GP 
1 2
PC28
SC2K2P50V3KX-GP
NOPOP
1 2
PG3
COPPER-CLOSE-GP-U
1 2
PR36
0R2J-2-GP 
1 2
PC37
SC100U6D3V6MX-GP 
1206
X5R
1 2
PL2
BLM21PG220SN1DGP
1 2
PR32 866KR2F-GPNOPOP1 2
PC36
SC22U6D3V3MX-1-GP 
1 2
PR24
2K7R2J-GP
NOPOP
1 2
PR37
10KR2F-2-GP 
1 2
PC22
SC22U25V5MX-GP 
1 2
PC27
SCD1U50V3KX-GP 
1 2PC26
SC4D7U25V5KX-1-GP
1 2
PU2
TPS53318DQPR-GP
VFB 1PGOOD3
EN2
VBST 4
ROVP 5
LL#6 6
LL#7 7
LL#8 8
LL#9 9
LL#10 10
LL#11 11
VIN 12 VIN 13 VIN 14 VIN 15 VIN 16 VIN 17 
VREG18
VDD19
MODE20
TRIP21
RF22
GND 23 
PR19
2D2R3J-2-GP
12
PC24
SC22U25V5MX-GP 
1 2
PR21
0R2J-2-GP
12
PC30SCD1U25V2KX-2-GP
1 2
PC39
SC100U6D3V6MX-GP 
1206
X5R
1 2
PL3
COIL-3D3UH-36-GP
1 2
PR30 100KR2F-L1-GPNOPOP1 2
PR29 475KR2F-GP1 2
PC33
SC1U10V2KX-1GP 
NOPOP12
PR25
10KR2F-2-GP
12
PR26
3K9R2F-GP
1 2
PR35 619KR2F-GPNOPOP1 2



5
5
4
4
3
3
2
2
1
1
D D
C C
B B
A A
FCCM Mode 
Vout=0.6x(1+Ru/Rd)=1.8 
SS=5.6ms 
OCP = 8.5A 
Power rail : P1V8_STBY(1.8V) 
Controller : TPS53318 (Fswitching=500KHz) 
TDC : 3.7A 
MAX : 3.7A 
OCP : 7A 
FS=500KHz 
P1V8_STBYP1V8_STBY_ROVP
P1V8_STBY_VIN
P1V8_STBY_VREG
P1V8_STBY_LL
P1V8_STBY_EN
P1V8_STBY_RF
P1V8_STBY_VREG
P1V8_STBY_TRIP
P1V8_STBY_VBST 
P1V8_STBY_MODE
P1V8_STBY_OUT
P1V8_STBY_VBST_RC
P1V8_STBY_VDD
P1V8_STBY_SNB
P1V8_STBY_VFB_R 
P1V8_STBY_LL_R
P1V8_STBY_VFB
P1V8_STBY
P1V8_STBY_OUT
P12V
AGND_P1V8_STBY
AGND_P1V8_STBY
AGND_P1V8_STBY
AGND_P1V8_STBY
P12V
AGND_P1V8_STBY
P5V_STBY
AGND_P1V8_STBY
P1V8_STBY_VREG
P1V8_STBY_PG44,59
P3V3_STBY_PG37,57
Title 
Size Document Number R e v 
Date: Sheet 
o f 
Honey badger_LSI Base Board 1B
PWRSW_P1V8_STBY_TPS53318
A3
58 71Tuesday, January 20, 2015
Honey badger_LSI Base Board
http://www.wiwynn.com
8F, 90, Sec.1, Xintai 5th Rd., Xizhi Dist.,
New Taipei City 22102, Taiwan (R.O.C.)
Title 
Size Document Number R e v 
Date: Sheet 
o f 
Honey badger_LSI Base Board 1B
PWRSW_P1V8_STBY_TPS53318
A3
58 71Tuesday, January 20, 2015
Honey badger_LSI Base Board
http://www.wiwynn.com
8F, 90, Sec.1, Xintai 5th Rd., Xizhi Dist.,
New Taipei City 22102, Taiwan (R.O.C.)
Title 
Size Document Number R e v 
Date: Sheet 
o f 
Honey badger_LSI Base Board 1B
PWRSW_P1V8_STBY_TPS53318
A3
58 71Tuesday, January 20, 2015
Honey badger_LSI Base Board
http://www.wiwynn.com
8F, 90, Sec.1, Xintai 5th Rd., Xizhi Dist.,
New Taipei City 22102, Taiwan (R.O.C.)
PR55 619KR2F-GPNOPOP1 2
PR46
3K9R2F-GP
1 2
PC59
SC100U6D3V6MX-GP 
1206
X5R
1 2
PR52 866KR2F-GPNOPOP1 2 PR53 20KR2F-L-GP
1 2
PR38
1K4R2F-1-GP
NOPOP
1 2
PR54 0R2J-2-GP
NOPOP
1 2
PC55
SCD1U16V3KX-3GP 
0603
X7R
1 2
PR44
2K7R2J-GP
NOPOP
1 2 PC46
SC4D7U25V5KX-1-GP
1 2
PR49
3D01R5F-GP
NOPOP
1 2
PC45
SCD1U25V3KX-GP 
1 2
PC44
SC22U25V5MX-GP 
1 2
PR45
10KR2F-2-GP
12
PC43
SC22U25V5MX-GP 
1 2
PL5
IND-2D2UH-122-GP
1 2
PR39
2D2R3J-2-GP
12
PC53
SC1U10V2KX-1GP 
NOPOP12
PR51 73K2R2F-GP1 2
PR47
10R3F-GP
1 2
PC48
SC2K2P50V3KX-GP
NOPOP
1 2
PR57
10KR2F-2-GP 
1 2
PC47
SCD1U50V3KX-GP 
1 2
PC49 SC1U10V3KX-4GP-U
1 2
PR56
0R2J-2-GP 
1 2
PU3
TPS53318DQPR-GP
VFB 1PGOOD3
EN2
VBST 4
ROVP 5
LL#6 6
LL#7 7
LL#8 8
LL#9 9
LL#10 10
LL#11 11
VIN 12 VIN 13 VIN 14 VIN 15 VIN 16 VIN 17 
VREG18
VDD19
MODE20
TRIP21
RF22
GND 23 
PR50 100KR2F-L1-GPNOPOP1 2
PC50
SCD1U25V2KX-2-GP
1 2
PC57
SC100U6D3V6MX-GP 
1206
X5R
1 2
PL4
BLM21PG220SN1DGP
1 2
PR41
3D01R5F-GP
1 2PR40
0R2J-2-GP
12
PC51
SC1KP50V2KX-1GP
1 2
PC58
SC100U6D3V6MX-GP 
1206
X5R
1 2
PC56
SC22U6D3V3MX-1-GP 
1 2
PC42
SC22U25V5MX-GP 
1 2
PR48 475KR2F-GP1 2
PC41
SC22U25V5MX-GP 
1 2
PG4
COPPER-CLOSE-GP-U
1 2



5
5
4
4
3
3
2
2
1
1
D D
C C
B B
A A
Power rail :P1V53_STBY(1.538V) 
Controller :TPS74801 
TDC :0.37A 
Max :0.37A 
OCP:2A 
TPS74801_1V53_STBY_BIAS
TPS74801_1V53_STBY_FBTPS74801_1V53_STBY_EN
TPS74801_1V53_STBY_SS
TPS74801_P1V53_STBY_IN TPS74801_1V53_STBY_OUT
P1V8_STBY
P1V53_STBY
P3V3_STBY
P3V3_STBY
P3V3_STBY
P1V53_STBY_PG 60
P1V8_STBY_PG44,58
Title 
Size Document Number R e v 
Date: Sheet 
o f 
Honey badger_LSI Base Board 1B
PWRLDO_P1V53_STBY_TPS74801
A3
59 71Tuesday, January 20, 2015
Honey badger_LSI Base Board
http://www.wiwynn.com
8F, 90, Sec.1, Xintai 5th Rd., Xizhi Dist.,
New Taipei City 22102, Taiwan (R.O.C.)
Title 
Size Document Number R e v 
Date: Sheet 
o f 
Honey badger_LSI Base Board 1B
PWRLDO_P1V53_STBY_TPS74801
A3
59 71Tuesday, January 20, 2015
Honey badger_LSI Base Board
http://www.wiwynn.com
8F, 90, Sec.1, Xintai 5th Rd., Xizhi Dist.,
New Taipei City 22102, Taiwan (R.O.C.)
Title 
Size Document Number R e v 
Date: Sheet 
o f 
Honey badger_LSI Base Board 1B
PWRLDO_P1V53_STBY_TPS74801
A3
59 71Tuesday, January 20, 2015
Honey badger_LSI Base Board
http://www.wiwynn.com
8F, 90, Sec.1, Xintai 5th Rd., Xizhi Dist.,
New Taipei City 22102, Taiwan (R.O.C.)
PC78
SCD1U16V2KX-3GP 
X7R
0.1uF
16V
0402
1 2
PR82
2K7R2J-GP
12
PC79
SC10U6D3V5KX-1GP 
1 2
PC83
SC10U6D3V5KX-1GP 
1 2
PR79
4K42R2F-GP
1 2
PC81
SC1KP50V2KX-1GP 
NOPOP
1 2
PR83
0R2J-2-GP
1 2
PC86
SCD1U10V2KX-5GP
1 2
PR78
0R6J-3-GP
1 2
PC87
SC470P50V2KX-3GP
1 2
PC80
SC10U6D3V5KX-1GP 
1 2
PC85
SC10U6D3V5KX-1GP 
1 2
PC88
SCD1U16V2KX-3GP
1 2
PR77
0R6J-3-GP
1 2
PU5
TPS74801RGW-GP
OUT#1 1
NC#2 2
NC#3 3
NC#4 4
IN#55 IN#66 IN#77 IN#88
PG 9
BIAS 10 
EN 11 
GND 12 
NC#13 13 
NC#14 14 
SS 15 
FB 16 
NC#17 17 
OUT#18 18
OUT#19 19
OUT#20 20
GND 21 
PR81
0R2J-2-GP
1 2
PC89
SCD1U16V2KX-3GP
NOPOP
1 2
PR80
4K75R2F-1-GP
1 2
R456
4K75R2F-1-GP
NOPOP
1 2
PC84
SC10U6D3V5KX-1GP 
1 2
PC82
SC10U6D3V5KX-1GP 
1 2



5
5
4
4
3
3
2
2
1
1
D D
C C
B B
A A
Power rail :P1V26_STBY(1.26V) 
Controller :TPS74801 
TDC :0.695A 
Max :0.695A 
OCP:2A 
TPS74801_1V26_STBY_BIAS
TPS74801_1V26_STBY_OUT
TPS74801_1V26_STBY_EN
TPS74801_1V26_STBY_SS
TPS74801_P1V26_STBY_IN
TPS74801_1V26_STBY_FB
P1V8_STBY
P1V26_STBY
P3V3_STBY
P3V3_STBY
P3V3_STBY
P1V26_STBY_PG 44,65
P1V53_STBY_PG59
Title 
Size Document Number R e v 
Date: Sheet 
o f 
Honey badger_LSI Base Board 1B
PWRLDO_P1V26_STBY_TPS74801
A3
60 71Tuesday, January 20, 2015
Honey badger_LSI Base Board
http://www.wiwynn.com
8F, 90, Sec.1, Xintai 5th Rd., Xizhi Dist.,
New Taipei City 22102, Taiwan (R.O.C.)
Title 
Size Document Number R e v 
Date: Sheet 
o f 
Honey badger_LSI Base Board 1B
PWRLDO_P1V26_STBY_TPS74801
A3
60 71Tuesday, January 20, 2015
Honey badger_LSI Base Board
http://www.wiwynn.com
8F, 90, Sec.1, Xintai 5th Rd., Xizhi Dist.,
New Taipei City 22102, Taiwan (R.O.C.)
Title 
Size Document Number R e v 
Date: Sheet 
o f 
Honey badger_LSI Base Board 1B
PWRLDO_P1V26_STBY_TPS74801
A3
60 71Tuesday, January 20, 2015
Honey badger_LSI Base Board
http://www.wiwynn.com
8F, 90, Sec.1, Xintai 5th Rd., Xizhi Dist.,
New Taipei City 22102, Taiwan (R.O.C.)
PU6
TPS74801RGW-GP
OUT#1 1
NC#2 2
NC#3 3
NC#4 4
IN#55 IN#66 IN#77 IN#88
PG 9
BIAS 10 
EN 11 
GND 12 
NC#13 13 
NC#14 14 
SS 15 
FB 16 
NC#17 17 
OUT#18 18
OUT#19 19
OUT#20 20
GND 21 
PR87
4K75R2F-1-GP
1 2
PC101
SCD1U16V2KX-3GP
NOPOP
1 2
PR86
2K74R2F-GP
1 2
PC97
SC10U6D3V5KX-1GP 
1 2
PC92
SC10U6D3V5KX-1GP 
1 2
PC94
SC10U6D3V5KX-1GP 
1 2
PC93
SC1KP50V2KX-1GP 
NOPOP
1 2
PR88
0R2J-2-GP
1 2
PC90
SCD1U16V2KX-3GP 
X7R
0.1uF
16V
0402
1 2
PC91
SC10U6D3V5KX-1GP 
1 2
PC100
SC470P50V2KX-3GP
1 2
PC102
SCD1U16V2KX-3GP
1 2
PC99
SCD1U10V2KX-5GP
1 2
PR90
0R2J-2-GP
1 2
PR84
0R6J-3-GP
1 2
PC96
SC10U6D3V5KX-1GP 
1 2
PR85
0R6J-3-GP
1 2
PC95
SC10U6D3V5KX-1GP 
1 2
R457
4K75R2F-1-GP
NOPOP
1 2
PR89
2K7R2J-GP
NOPOP
12



5
5
4
4
3
3
2
2
1
1
D D
C C
B B
A A
Power rail :P1V5_C(1.5V) 
Controller :TPS74801 
TDC :0.36A 
Max :0.36A 
OCP:2A 
TPS74801_1V5_C_BIAS
TPS74801_1V5_C_EN
TPS74801_1V5_C_SS
TPS74801_P1V5_C_IN TPS74801_1V5_C_OUT
TPS74801_1V5_C_FB
P3V3_STBY
P1V8_STBY
P3V3_STBY
P3V3_STBY
P1V5_C
PWRGD_P1V5_C_PG 63
P1V8_C_PG13,65
Title 
Size Document Number R e v 
Date: Sheet 
o f 
Honey badger_LSI Base Board 1B
PWRLDO_P1V5_C_TPS74801
A3
61 71Tuesday, January 20, 2015
Honey badger_LSI Base Board
http://www.wiwynn.com
8F, 90, Sec.1, Xintai 5th Rd., Xizhi Dist.,
New Taipei City 22102, Taiwan (R.O.C.)
Title 
Size Document Number R e v 
Date: Sheet 
o f 
Honey badger_LSI Base Board 1B
PWRLDO_P1V5_C_TPS74801
A3
61 71Tuesday, January 20, 2015
Honey badger_LSI Base Board
http://www.wiwynn.com
8F, 90, Sec.1, Xintai 5th Rd., Xizhi Dist.,
New Taipei City 22102, Taiwan (R.O.C.)
Title 
Size Document Number R e v 
Date: Sheet 
o f 
Honey badger_LSI Base Board 1B
PWRLDO_P1V5_C_TPS74801
A3
61 71Tuesday, January 20, 2015
Honey badger_LSI Base Board
http://www.wiwynn.com
8F, 90, Sec.1, Xintai 5th Rd., Xizhi Dist.,
New Taipei City 22102, Taiwan (R.O.C.)
PC145
SC10U6D3V5KX-1GP 
1 2
PC138
SCD1U16V2KX-3GP 
X7R
0.1uF
16V
0402
1 2
PR122
4K22R2F-GP
1 2
PC146
SCD1U10V2KX-5GP
1 2
PC139
SC10U6D3V5KX-1GP 
1 2
PC148
SCD1U16V2KX-3GP
1 2
PC141
SC1KP50V2KX-1GP 
NOPOP
1 2
PC149
SCD1U16V2KX-3GP
NOPOP
1 2
PR120
0R6J-3-GP
1 2
PC147
SC470P50V2KX-3GP
1 2
PR125
2K7R2J-GP
12
PU10
TPS74801RGW-GP
OUT#1 1
NC#2 2
NC#3 3
NC#4 4
IN#55 IN#66 IN#77 IN#88
PG 9
BIAS 10 
EN 11 
GND 12 
NC#13 13 
NC#14 14 
SS 15 
FB 16 
NC#17 17 
OUT#18 18
OUT#19 19
OUT#20 20
GND 21 
PR124
0R2J-2-GP
1 2
R598
4K75R2F-1-GP
NOPOP
1 2
PC143
SC10U6D3V5KX-1GP 
1 2
PC144
SC10U6D3V5KX-1GP 
1 2
PC140
SC10U6D3V5KX-1GP 
1 2
PR123
4K75R2F-1-GP
1 2
PC142
SC10U6D3V5KX-1GP 
1 2
PR126
0R2J-2-GP
1 2



5
5
4
4
3
3
2
2
1
1
D D
C C
B B
A A
P3V3_EN_G
P3V3_EN_LV
P3V3_S_LV
P3V3_EN_LV
P3V3_STBY_R1
P3V3_EN_B
P3V3_STBY_B1
P3V3_PG_R
P3V3_B
P12V
P3V3_STBY P3V3
P3V3_STBY P12VP3V3_STBY
P3V3_STBY
P3V3
P3V3
BMC_EN_P3V343
P0V9_E_PG25,33,43,64
P3V3_PG 65
Title 
Size Document Number R e v 
Date: Sheet 
o f 
Honey badger_LSI Base Board 1B
PWRMOS_P3V3
A3
62 71Tuesday, January 20, 2015
Honey badger_LSI Base Board
http://www.wiwynn.com
8F, 90, Sec.1, Xintai 5th Rd., Xizhi Dist.,
New Taipei City 22102, Taiwan (R.O.C.)
Title 
Size Document Number R e v 
Date: Sheet 
o f 
Honey badger_LSI Base Board 1B
PWRMOS_P3V3
A3
62 71Tuesday, January 20, 2015
Honey badger_LSI Base Board
http://www.wiwynn.com
8F, 90, Sec.1, Xintai 5th Rd., Xizhi Dist.,
New Taipei City 22102, Taiwan (R.O.C.)
Title 
Size Document Number R e v 
Date: Sheet 
o f 
Honey badger_LSI Base Board 1B
PWRMOS_P3V3
A3
62 71Tuesday, January 20, 2015
Honey badger_LSI Base Board
http://www.wiwynn.com
8F, 90, Sec.1, Xintai 5th Rd., Xizhi Dist.,
New Taipei City 22102, Taiwan (R.O.C.)
S
S
S
GD
D
D
D
PQ1
AO4406AL-GP
1
2
3
45
6
7
8
R578 4K7R2F-GP
1 2
R579
0R2J-2-GP
12
PC137
SCD47U25V3KX-3-GP
1 2
PR116
20KR2F-L-GP
1 2
Q11
2N7002A-7-GP
G
SD
PR118
1KR2F-3-GP
1 2
PR58
0R2J-2-GP
12
C321
SCD1U16V2KX-3GP
NOPOP
1 2
R576
1KR2J-1-GP
12
PQ2 2N7002A-7-GP
NOPOP
G
S D
PR131
0R2J-2-GP
NOPOP
1 2
PR114
4K02R2F-GP
NOPOP
12
Q12
2N7002A-7-GP
G
SD
R580
4K7R2F-GP
12
PR117
0R2J-2-GP
1 2
PR115
4K02R2F-GP
12
PU9
2N7002DW-7F-GP
1
2
3 4
5
6
PR119
10KR2F-2-GP
1 2



5
5
4
4
3
3
2
2
1
1
D D
C C
B B
A A
Power rail :P0V955_C(0.955V) 
Controller :TPS53353 
Fswitch= 300KHz 
TDC : TBD 
Max : 14.37A 
OCP :20A 
Ra 
Ca 
Rb 
Rc 
Rd 
VT235_EN
VT235_VDES_RC 
VT235_IRIP
VT235_VDDH
VT235_PGIN
VT235_BIAS
VT235_VDES
VT235_PGIN
VT235_BST
VT235_VFB
VT235_VDES_RCC
VT235_IMAX
VT235_VREF
VT235_VX
VT235_VREF
VT235_AVDD
VT235_VDDL
VT235_VDES_RR 
P0V955_C_PG_R
P3V3_STBY_G9P3V3_STBY_R9
PG_STAT_P0V955_C
PWRGD_P0V955_C
PG_STAT
P3V3
P12V
AGND_P0V9_C
AGND_P0V9_C AGND_P0V9_C
P0V955_C
P0V955_C
AGND_P0V9_C
P1V8_C
P3V3_STBY
P3V3_STBY
P1V8_C
AVSO_VREF13PWRGD_P1V5_C_PG61
BMC_EN_0V955_C43
PG_STAT_P0V955_C 43
PWRGD_P0V955_C 13
Title 
Size Document Number Rev 
Date: Sheet o f 
Honey badger_LSI Base Board 1B
PWRSW_P0V955_C_VT235WFQX
A2
63 71Tuesday, January 20, 2015
Honey badger_LSI Base Board
http://www.wiwynn.com
8F, 90, Sec.1, Xintai 5th Rd., Xizhi Dist.,
New Taipei City 22102, Taiwan (R.O.C.)
Title 
Size Document Number Rev 
Date: Sheet o f 
Honey badger_LSI Base Board 1B
PWRSW_P0V955_C_VT235WFQX
A2
63 71Tuesday, January 20, 2015
Honey badger_LSI Base Board
http://www.wiwynn.com
8F, 90, Sec.1, Xintai 5th Rd., Xizhi Dist.,
New Taipei City 22102, Taiwan (R.O.C.)
Title 
Size Document Number Rev 
Date: Sheet o f 
Honey badger_LSI Base Board 1B
PWRSW_P0V955_C_VT235WFQX
A2
63 71Tuesday, January 20, 2015
Honey badger_LSI Base Board
http://www.wiwynn.com
8F, 90, Sec.1, Xintai 5th Rd., Xizhi Dist.,
New Taipei City 22102, Taiwan (R.O.C.)
PC215 
SC1U25V3KX-GP 
1 2
PR185 69K8R2F-GP1 2
PC199
SC22U6D3V6KX-2-GP 
1 2
PC202
SC22U6D3V6KX-2-GP 
1 2
SR931
10KR2F-2-GP
1 2
PR179
10KR2F-2-GP 
12
SR851
4K7R2F-GP
1 2
PSP3
COPPER-CLOSE-GP-U
1 2
SR932
4K7R2F-GP
1 2
PR181
19K1R2F-GP
1 2
PC204
SC10U25V6KX-1GP 
1 2
PC194
SC6800P50V3KX-GP 
1 2
PC218 
SCD01U50V3KX-4GP 
1 2
PR188 
100KR2F-L1-GP 
NOPOP1 2
PR182
221R2F-2-GP
1 2
PC195
SCD1U50V3KX-GP 
1 2
PC221 
SC1KP50V2KX-1GP 
1 2
PL10
BLM41PG600-GP
1 2
PC222 
SCD33U6D3V2KX-1-GP 
1 2
PC208 
SC1U25V3KX-GP 
1 2
PL11
IND-D47UH-22-GP
1 2
PC196
SC22U6D3V6KX-2-GP 
1 2
PC207 
SC1U25V3KX-GP 
1 2
PC216
SC22U25V5MX-GP 
1 2
PR194 
287R2F-GP 
1 2
PR195
0R2J-2-GP
NOPOP
12
PC197
SC22U6D3V6KX-2-GP 
1 2
PC198
SC22U6D3V6KX-2-GP 
1 2
PC219
SCD1U50V3KX-GP 
1 2
PR184 10KR2F-2-GP1 2
PC200
SC22U6D3V6KX-2-GP 
1 2
PC193
SC1U50V3KX-GP
1 2
PC223
SCD1U50V3KX-GP 
1 2
SR929
0R2J-2-GP
12
PC210
SCD01U50V3KX-4GP 
1 2
PC203
SC22U6D3V6KX-2-GP 
1 2
PR190 
7K32R2F-GP 
1 2
SQ18
2N7002A-7-GP
G
SD
SR930
4K7R2F-GP
1 2
PC217 
SC220P50V2KX-3GP 
1 2
PR183 
1K21R2F-2-GP 
1 2
PC213 
SC1U25V3KX-GP 
1 2
PR191
221R2F-2-GP
1 2
PC214
SC6800P50V3KX-GP 
1 2
PR187 
100KR2F-L1-GP 
1 2
PU13
VT235WFQX-ADJ-1-GP
STAT 17
EN18
IMAX16
IRPL19
VBIAS15
VDDL9
RES110
AVDD3
VDDH4
BST8
VX#6 6
VX#7 7
PGIN12
VFB 11
VDES 13
VREF14
NODR2
AGND1 GND 5
SQ11
2N7002A-7-GP
G
SD
PC212 
SC1U25V3KX-GP 
1 2
PC206
SC10U25V6KX-1GP 
1 2
PR192
0R2J-2-GP
12
PR186 10KR2F-2-GP1 2
PC220
SC1U10V2KX-1GP
NOPOP
12
PC205
SC10U25V6KX-1GP 
1 2
PC211
SCD01U50V3KX-4GP 
1 2
PC209 
SC1U25V3KX-GP 
1 2
PU99
SNLVC1G17DCKR-GP
NC#11
A2
GND3 Y 4
VCC 5
PR189
10KR2F-2-GP
NOPOP
12
PC201
SC22U6D3V6KX-2-GP 
1 2



5
5
4
4
3
3
2
2
1
1
D D
C C
B B
A A
Power rail :P0V9_E 
Controller :TPS53355 
Fswitch= 300KHz 
TDC : 21.85 
Max : 21.85A 
OCP :28A 
P0V9_E  SWITCHING TPS53355 
P0V9_E_VREG
P0V9_E_MODE
P0V9_E_VIN
P0V9_E_SW_R
P0V9_E_EN
P0V9_E_VBST
P0V9_E_TRIP
P0V9_E_VBST_RC
P0V9_E_RF
P0V9_E_VDD
P0V9_E_VFB_R P0V9_E_SNB
P0V9_E_VFB
P0V9_E_LX
AGND_P0V9_E
AGND_P0V9_E
AGND_P0V9_E
P12V
AGND_P0V9_E
P12V
P3V3_STBY
P0V9_E
P0V9_E
P1V5_E_PG66
P0V9_E_PG25,33,43,62
Title 
Size Document Number Rev 
Date: Sheet o f 
Honey badger_LSI Base Board 1B
PWRSW_P0V9_E_TPS53355
A2
64 71Tuesday, January 20, 2015
Honey badger_LSI Base Board
http://www.wiwynn.com
8F, 90, Sec.1, Xintai 5th Rd., Xizhi Dist.,
New Taipei City 22102, Taiwan (R.O.C.)
Title 
Size Document Number Rev 
Date: Sheet o f 
Honey badger_LSI Base Board 1B
PWRSW_P0V9_E_TPS53355
A2
64 71Tuesday, January 20, 2015
Honey badger_LSI Base Board
http://www.wiwynn.com
8F, 90, Sec.1, Xintai 5th Rd., Xizhi Dist.,
New Taipei City 22102, Taiwan (R.O.C.)
Title 
Size Document Number Rev 
Date: Sheet o f 
Honey badger_LSI Base Board 1B
PWRSW_P0V9_E_TPS53355
A2
64 71Tuesday, January 20, 2015
Honey badger_LSI Base Board
http://www.wiwynn.com
8F, 90, Sec.1, Xintai 5th Rd., Xizhi Dist.,
New Taipei City 22102, Taiwan (R.O.C.)
PR155
2K21R2F-GP
1 2
PC177
SC22U6D3V3MX-1-GP 
1 2
PC175
SC22U25V5MX-GP 
1 2
PTC4
SE470UF2VDM-GP 
1 2
PC189
SC1KP50V2KX-1GP
1 2PR162
187KR2F-GP
1 2
PR158
100KR2F-L1-GPNOPOP
1 2
PC182
SC47U6D3V5MX-1-GP 
0805
X5R
1 2
PL8
BLM41PG600-GP
1 2
PL9
IND-300NH-8-GP
1 2
PR160
475KR2F-GP
1 2
PC190
SC1U16V3KX-2GP
1 2
PC180
SC47U6D3V5MX-1-GP 
0805
X5R
1 2
PC184
SC4D7U25V5KX-1-GP
1 2
PC176
SC22U6D3V3MX-1-GP 
1 2
PC181
SC47U6D3V5MX-1-GP 
0805
X5R
1 2
PR151
100KR2F-L1-GPNOPOP
1 2
PR164
113KR2F-1-GP
1 2
PTC7
SE470UF2VDM-GP 
1 2
PR152
0R2J-2-GP
12
R610 4K7R2F-GP
1 2
PC185
SCD1U50V3KX-GP
1 2
PU12
TPS53355DQPR-GP
VFB 1PGOOD3
EN2
VBST 4
NC#5 5
LL#6 6
LL#7 7
LL#8 8
LL#9 9
LL#10 10
LL#11 11
VIN 12 VIN 13 VIN 14 VIN 15 VIN 16 VIN 17 
VREG18
VDD19
MODE20
TRIP21
RF22
GND 23 
PC171
SC22U25V5MX-GP 
1 2
PC186
SCD1U16V2KX-3GP
1 2
PC178
SC22U6D3V3MX-1-GP 
1 2
PC183
SC47U6D3V5MX-1-GP 
0805
X5R
1 2 PTC5
SE470UF2VDM-GP 
1 2
PR153
0R5J-5-GP
1 2
PR161
4K87R2F-GP
1 2
PR163
100KR2F-L1-GP
NOPOP
1 2
PC187
SC1U10V2KX-1GP
NOPOP
12
PR150
0R3J-0-U-GP
1 2
PR154
3D01R5F-GP
NOPOP
1 2
PC173
SC22U25V5MX-GP 
1 2
PC172
SCD1U50V3KX-GP 
1 2
PC174
SC22U25V5MX-GP 
1 2
PC169
SC22U25V5MX-GP 
1 2
PC188
SC470P50V2KX-3GP
NOPOP
1 2
PR157
51KR2F-L-GP
NOPOP
1 2
PTC6
SE470UF2VDM-GP 
1 2
PR156
10D7R2F-GP
12
PR165
10KR2F-2-GP
1 2
PC170
SC22U25V5MX-GP 
1 2
PC179
SC22U6D3V3MX-1-GP 
1 2
PSP2
COPPER-CLOSE-GP-U
1 2



5
5
4
4
3
3
2
2
1
1
D D
C C
B B
A A
P1V8_EN_LVP1V8_EN_S
P1V8_EN_G
P1V8_E_B
P1V8_PG_R_1
P3V3_STBY_R2
P1V8_PG_R_2
P3V3_STBY_R3
P1V8_C_EN_G
P1V8_C_EN_LV
P3V3_STBY_B2
P3V3_STBY_B3
P1V8_C_B
P1V8_C_EN_B
P1V8_STBY
P3V3_STBY P12VP3V3_STBY
P1V8_E
P1V8_E
P5V_STBY
P3V3_STBY
P1V8_STBY
P3V3_STBY
P1V8_C
P1V8_STBY
P3V3_STBY P12VP3V3_STBY
P1V8_C
P1V26_STBY_PG44,60
P1V8_E_PG 66
P1V8_C_PG 13,61
P3V3_PG62
BMC_1V8_C_EN43
Title 
Size Document Number R e v 
Date: Sheet 
o f 
Honey badger_LSI Base Board 1B
PWRMOS_P1V8_C & P1V8_E
A3
65 71Tuesday, January 20, 2015
Honey badger_LSI Base Board
http://www.wiwynn.com
8F, 90, Sec.1, Xintai 5th Rd., Xizhi Dist.,
New Taipei City 22102, Taiwan (R.O.C.)
Title 
Size Document Number R e v 
Date: Sheet 
o f 
Honey badger_LSI Base Board 1B
PWRMOS_P1V8_C & P1V8_E
A3
65 71Tuesday, January 20, 2015
Honey badger_LSI Base Board
http://www.wiwynn.com
8F, 90, Sec.1, Xintai 5th Rd., Xizhi Dist.,
New Taipei City 22102, Taiwan (R.O.C.)
Title 
Size Document Number R e v 
Date: Sheet 
o f 
Honey badger_LSI Base Board 1B
PWRMOS_P1V8_C & P1V8_E
A3
65 71Tuesday, January 20, 2015
Honey badger_LSI Base Board
http://www.wiwynn.com
8F, 90, Sec.1, Xintai 5th Rd., Xizhi Dist.,
New Taipei City 22102, Taiwan (R.O.C.)
Q80
MMBT3904TT1G-GP
C
B
E
R599 4K7R2F-GP
1 2
PR171
1KR2J-1-GP
12
R606
4K7R2F-GP
12
PR168
100KR2F-L1-GP
1 2
PQ5 2N7002A-7-GPG
S D
PR174
4K02R2F-GP
NOPOP
12
PQ4
2N7002A-7-GP
G
S D
R605
0R2J-2-GP
12
R604
1KR2J-1-GP
12
PR176
0R2J-2-GP
1 2
PR172
0R2J-2-GP
12
PR177
1KR2F-3-GP
1 2
Q97
2N7002A-7-GP
G
SD
PR180
0R2J-2-GP
NOPOP
1 2
R603 4K7R2F-GP
1 2
PR173
4K02R2F-GP
12
PQ6
2N7002A-7-GP
G
SD
Q78
FDN359BN-GP-U
G
D S
PC191
SCD47U25V3KX-3-GP
1 2
PC192
SCD47U25V3KX-3-GP
1 2
PR175
20KR2F-L-GP
1 2
PR167
4K02R2F-GP
12
R602
4K7R2F-GP
12 Q77
MMBT3904TT1G-GP
C
B
E
R601
0R2J-2-GP
12
PR166
4K02R2F-GP
NOPOP
12
R600
1KR2J-1-GP
12
PR178
0R2J-2-GP
12
PQ3
FDN359BN-GP-U
G
D S
PR169
0R2J-2-GP
12



5
5
4
4
3
3
2
2
1
1
D D
C C
B B
A A
Power rail :P1V5_E 
Controller : TPS53312 (Fswitching=700KHz) 
TDC :1.9A 
MAX :3A 
OCP :4.1A 
SS=1.26ms 
P1V5_E_VRG5
P1V5_E_SNB
P1V5_E_VIN
P1V5_E_CC
P1V5_E_VBST_RR
P1V5_E_OUT
P1V5_E_EN_R
P1V5_E_VO
P1V5_E_VFB
P1V5_E_SS
P1V5_E_VBST
P1V5_E_VFB
P1V5_E_CC 
P1V5_E_VIN
P1V5_E_VFB_R
P1V5_E_CC_R
P1V5_E_VCC
P1V5_E_SW
AGND_P1V5_E
AGND_P1V5_E
AGND_P1V5_E
P12V
AGND_P1V5_E 
P1V5_E
P3V3_STBY
P1V5_E_PG64
P1V8_E_PG65
Title 
Size Document Number R e v 
Date: Sheet 
o f 
Honey badger_LSI Base Board 1B
PWRMOS_P1V8_C & P1V8_E
A3
66 71Tuesday, January 20, 2015
Title 
Size Document Number R e v 
Date: Sheet 
o f 
Honey badger_LSI Base Board 1B
PWRMOS_P1V8_C & P1V8_E
A3
66 71Tuesday, January 20, 2015
Title 
Size Document Number R e v 
Date: Sheet 
o f 
Honey badger_LSI Base Board 1B
PWRMOS_P1V8_C & P1V8_E
A3
66 71Tuesday, January 20, 2015
PG6
COPPER-CLOSE-GP-U
1 2
PC230
SC3300P50V2KX-1GP
1 2 PG5
GAP-CLOSE-PWR-4-GP 
1 2
PC226
SC22U25V5MX-GP 
1 2
PC232
SC1U16V3KX-5GP
1 2
PC228 SC1U10V2KX-1GP
NOPOP
1 2
PC236
SC22U6D3V5MX-2GP 
1 2
PC227
SC22U25V5MX-GP 
1 2
PC237
SC47U6D3V5MX-1-GP 
0805
X5R
1 2
PC234
SCD1U16V2KX-3GP 
1 2
R9014 9K53R2F-GP1 2
PR9017
10KR2F-2-GP
12
PC231
SC2K2P50V3KX-GP
NOPOP
1 2
PR9019
3D01R5F-GP
NOPOP
1 2
PR9009
0R6J-3-GP
1 2
PC235
SC22U6D3V5MX-2GP 
1 2
PC238
SC47U6D3V5MX-1-GP 
0805
X5R
1 2
PC233
SCD1U50V3KX-GP 
NOPOP
12
PC225
SCD1U16V2KX-3GP 
1 2
PR9010 10KR2F-2-GP1 2
PC240
SC1U10V2KX-1GP
NOPOP
12
PR9008
2D2R3J-2-GP
1 2
PC229
SCD1U50V3KX-GP
12
PC224
SC1U16V3KX-5GP 
1 2
PR9013
10R3F-GP
1 2
PU100
TPS53312RGTR-GP
VBST 12
VIN#13 13
SW#9 9
VREG52
PG5
GND4
SS3
VFB1
VO16
VCC15
EN6 SW#10 10
SW#11 11
VIN#14 14
PGND 7
PGND 8GND17
PR9018
2KR2F-3-GP 
NOPOP1 2
PR9020
0R2J-2-GP
1 2
PR9016
0R2J-2-GP
12
PC239
SC1KP50V2KX-1GP 
NOPOP
1 2
PR9015 0R2J-2-GP 12
PR7889
4K75R2F-1-GP
NOPOP
1 2
PL12
COIL-3D3UH-26-GP
1 2



5
5
4
4
3
3
2
2
1
1
D D
C C
B B
A A
Title 
Size Document Number R e v 
Date: Sheet 
o f 
Honey badger_LSI Base Board 1B
UART TOPOLOGY
A3
67 71Tuesday, January 20, 2015
Honey badger_LSI Base Board
http://www.wiwynn.com
8F, 90, Sec.1, Xintai 5th Rd., Xizhi Dist.,
New Taipei City 22102, Taiwan (R.O.C.)
Title 
Size Document Number R e v 
Date: Sheet 
o f 
Honey badger_LSI Base Board 1B
UART TOPOLOGY
A3
67 71Tuesday, January 20, 2015
Honey badger_LSI Base Board
http://www.wiwynn.com
8F, 90, Sec.1, Xintai 5th Rd., Xizhi Dist.,
New Taipei City 22102, Taiwan (R.O.C.)
Title 
Size Document Number R e v 
Date: Sheet 
o f 
Honey badger_LSI Base Board 1B
UART TOPOLOGY
A3
67 71Tuesday, January 20, 2015
Honey badger_LSI Base Board
http://www.wiwynn.com
8F, 90, Sec.1, Xintai 5th Rd., Xizhi Dist.,
New Taipei City 22102, Taiwan (R.O.C.)



5
5
4
4
3
3
2
2
1
1
D D
C C
B B
A A
Title 
Size Document Number R e v 
Date: Sheet 
o f 
Honey badger_LSI Base Board 1B
JTAG 
A3
68 71Tuesday, January 20, 2015
Honey badger_LSI Base Board
http://www.wiwynn.com
8F, 90, Sec.1, Xintai 5th Rd., Xizhi Dist.,
New Taipei City 22102, Taiwan (R.O.C.)
Title 
Size Document Number R e v 
Date: Sheet 
o f 
Honey badger_LSI Base Board 1B
JTAG 
A3
68 71Tuesday, January 20, 2015
Honey badger_LSI Base Board
http://www.wiwynn.com
8F, 90, Sec.1, Xintai 5th Rd., Xizhi Dist.,
New Taipei City 22102, Taiwan (R.O.C.)
Title 
Size Document Number R e v 
Date: Sheet 
o f 
Honey badger_LSI Base Board 1B
JTAG 
A3
68 71Tuesday, January 20, 2015
Honey badger_LSI Base Board
http://www.wiwynn.com
8F, 90, Sec.1, Xintai 5th Rd., Xizhi Dist.,
New Taipei City 22102, Taiwan (R.O.C.)



5
5
4
4
3
3
2
2
1
1
D D
C C
B B
A A
BLANK 
Title 
Size Document Number R e v 
Date: Sheet 
o f 
Honey badger_LSI Base Board 1B
BLANK
A3
69 71Tuesday, January 20, 2015
Honey badger_LSI Base Board
http://www.wiwynn.com
8F, 90, Sec.1, Xintai 5th Rd., Xizhi Dist.,
New Taipei City 22102, Taiwan (R.O.C.)
Title 
Size Document Number R e v 
Date: Sheet 
o f 
Honey badger_LSI Base Board 1B
BLANK
A3
69 71Tuesday, January 20, 2015
Honey badger_LSI Base Board
http://www.wiwynn.com
8F, 90, Sec.1, Xintai 5th Rd., Xizhi Dist.,
New Taipei City 22102, Taiwan (R.O.C.)
Title 
Size Document Number R e v 
Date: Sheet 
o f 
Honey badger_LSI Base Board 1B
BLANK
A3
69 71Tuesday, January 20, 2015
Honey badger_LSI Base Board
http://www.wiwynn.com
8F, 90, Sec.1, Xintai 5th Rd., Xizhi Dist.,
New Taipei City 22102, Taiwan (R.O.C.)



5
5
4
4
3
3
2
2
1
1
D D
C C
B B
A A
BLANK 
Title 
Size Document Number R e v 
Date: Sheet 
o f 
Honey badger_LSI Base Board 1B
BLANK
A3
70 71Tuesday, January 20, 2015
Honey badger_LSI Base Board
http://www.wiwynn.com
8F, 90, Sec.1, Xintai 5th Rd., Xizhi Dist.,
New Taipei City 22102, Taiwan (R.O.C.)
Title 
Size Document Number R e v 
Date: Sheet 
o f 
Honey badger_LSI Base Board 1B
BLANK
A3
70 71Tuesday, January 20, 2015
Honey badger_LSI Base Board
http://www.wiwynn.com
8F, 90, Sec.1, Xintai 5th Rd., Xizhi Dist.,
New Taipei City 22102, Taiwan (R.O.C.)
Title 
Size Document Number R e v 
Date: Sheet 
o f 
Honey badger_LSI Base Board 1B
BLANK
A3
70 71Tuesday, January 20, 2015
Honey badger_LSI Base Board
http://www.wiwynn.com
8F, 90, Sec.1, Xintai 5th Rd., Xizhi Dist.,
New Taipei City 22102, Taiwan (R.O.C.)



5
5
4
4
3
3
2
2
1
1
D D
C C
B B
A A
BLANK 
Title 
Size Document Number R e v 
Date: Sheet 
o f 
Honey badger_LSI Base Board 1B
BLANK
A3
71 71Tuesday, January 20, 2015
Honey badger_LSI Base Board
http://www.wiwynn.com
8F, 90, Sec.1, Xintai 5th Rd., Xizhi Dist.,
New Taipei City 22102, Taiwan (R.O.C.)
Title 
Size Document Number R e v 
Date: Sheet 
o f 
Honey badger_LSI Base Board 1B
BLANK
A3
71 71Tuesday, January 20, 2015
Honey badger_LSI Base Board
http://www.wiwynn.com
8F, 90, Sec.1, Xintai 5th Rd., Xizhi Dist.,
New Taipei City 22102, Taiwan (R.O.C.)
Title 
Size Document Number R e v 
Date: Sheet 
o f 
Honey badger_LSI Base Board 1B
BLANK
A3
71 71Tuesday, January 20, 2015
Honey badger_LSI Base Board
http://www.wiwynn.com
8F, 90, Sec.1, Xintai 5th Rd., Xizhi Dist.,
New Taipei City 22102, Taiwan (R.O.C.)